# Altium SchDoc records: 11-M2_RCB_MUX.SchDoc
|HEADER=Protel for Windows - Schematic Capture Binary File Version 5.0|Weight=1678|MinorVersion=7
|RECORD=31|FontIdCount=2|Size1=10|FontName1=Times New Roman|Size2=10|Rotation2=90|FontName2=Times New Roman|UseMBCS=T|IsBOC=T|HotSpotGridOn=T|HotSpotGridSize=4|SheetStyle=6|SystemFont=1|BorderOn=T|TitleBlockOn=T|SheetNumberSpaceSize=12|AreaColor=16317695|SnapGridOn=T|SnapGridSize=10|VisibleGridOn=T|VisibleGridSize=10|CustomX=1500|CustomY=950|CustomXZones=6|CustomYZones=4|CustomMarginWidth=20|Display_Unit=0
|RECORD=41|OwnerPartId=-1|Color=8388608|FontID=1|IsHidden=T|Text=*|Name=CurrentTime|ReadOnlyState=1
|RECORD=41|IndexInSheet=1|OwnerPartId=-1|Color=8388608|FontID=1|IsHidden=T|Text=*|Name=CurrentDate|ReadOnlyState=1
|RECORD=41|IndexInSheet=2|OwnerPartId=-1|Color=8388608|FontID=1|IsHidden=T|Text=*|Name=Time|ReadOnlyState=1
|RECORD=41|IndexInSheet=3|OwnerPartId=-1|Color=8388608|FontID=1|IsHidden=T|Text=*|Name=Date|ReadOnlyState=1
|RECORD=41|IndexInSheet=4|OwnerPartId=-1|Color=8388608|FontID=1|IsHidden=T|Text=*|Name=DocumentFullPathAndName|ReadOnlyState=1
|RECORD=41|IndexInSheet=5|OwnerPartId=-1|Color=8388608|FontID=1|IsHidden=T|Text=*|Name=DocumentName|ReadOnlyState=1
|RECORD=41|IndexInSheet=6|OwnerPartId=-1|Color=8388608|FontID=1|IsHidden=T|Text=*|Name=ModifiedDate|ReadOnlyState=1
|RECORD=41|IndexInSheet=7|OwnerPartId=-1|Color=8388608|FontID=1|IsHidden=T|Text=*|Name=ApprovedBy|ReadOnlyState=1
|RECORD=41|IndexInSheet=8|OwnerPartId=-1|Color=8388608|FontID=1|IsHidden=T|Text=*|Name=CheckedBy|ReadOnlyState=1
|RECORD=41|IndexInSheet=9|OwnerPartId=-1|Color=8388608|FontID=1|IsHidden=T|Text=*|Name=Author|ReadOnlyState=1
|RECORD=41|IndexInSheet=10|OwnerPartId=-1|Color=8388608|FontID=1|IsHidden=T|Text=*|Name=CompanyName|ReadOnlyState=1
|RECORD=41|IndexInSheet=11|OwnerPartId=-1|Color=8388608|FontID=1|IsHidden=T|Text=*|Name=DrawnBy|ReadOnlyState=1
|RECORD=41|IndexInSheet=12|OwnerPartId=-1|Color=8388608|FontID=1|IsHidden=T|Text=*|Name=Engineer|ReadOnlyState=1
|RECORD=41|IndexInSheet=13|OwnerPartId=-1|Color=8388608|FontID=1|IsHidden=T|Text=*|Name=Organization|ReadOnlyState=1
|RECORD=41|IndexInSheet=14|OwnerPartId=-1|Color=8388608|FontID=1|IsHidden=T|Text=*|Name=Address1|ReadOnlyState=1
|RECORD=41|IndexInSheet=15|OwnerPartId=-1|Color=8388608|FontID=1|IsHidden=T|Text=*|Name=Address2|ReadOnlyState=1
|RECORD=41|IndexInSheet=16|OwnerPartId=-1|Color=8388608|FontID=1|IsHidden=T|Text=*|Name=Address3|ReadOnlyState=1
|RECORD=41|IndexInSheet=17|OwnerPartId=-1|Color=8388608|FontID=1|IsHidden=T|Text=*|Name=Address4|ReadOnlyState=1
|RECORD=41|IndexInSheet=18|OwnerPartId=-1|Color=8388608|FontID=1|IsHidden=T|Text=*|Name=Title|ReadOnlyState=1
|RECORD=41|IndexInSheet=19|OwnerPartId=-1|Color=8388608|FontID=1|IsHidden=T|Text=*|Name=DocumentNumber|ReadOnlyState=1
|RECORD=41|IndexInSheet=20|OwnerPartId=-1|Color=8388608|FontID=1|IsHidden=T|Text=*|Name=Revision|ReadOnlyState=1
|RECORD=41|IndexInSheet=21|OwnerPartId=-1|Color=8388608|FontID=1|IsHidden=T|Text=*|Name=SheetNumber|ReadOnlyState=1
|RECORD=41|IndexInSheet=22|OwnerPartId=-1|Color=8388608|FontID=1|IsHidden=T|Text=*|Name=SheetTotal|ReadOnlyState=1
|RECORD=41|IndexInSheet=23|OwnerPartId=-1|Color=8388608|FontID=1|IsHidden=T|Text=*|Name=Rule|ReadOnlyState=1
|RECORD=41|IndexInSheet=24|OwnerPartId=-1|Color=8388608|FontID=1|IsHidden=T|Text=*|Name=ImagePath|ReadOnlyState=1
|RECORD=41|IndexInSheet=25|OwnerPartId=-1|Color=8388608|FontID=1|IsHidden=T|Text=*|Name=ProjectName|ReadOnlyState=1
|RECORD=41|IndexInSheet=26|OwnerPartId=-1|Color=8388608|FontID=1|IsHidden=T|Text=*|Name=Application_BuildNumber|ReadOnlyState=1
|RECORD=1|LibReference=PI3A412ZHE|ComponentDescription=No Description Available|PartCount=2|DisplayModeCount=1|IndexInSheet=27|OwnerPartId=-1|Location.X=210|Location.Y=630|CurrentPartId=1|LibraryPath=*|SourceLibraryName=PI3A412ZHE.SchLib|TargetFileName=*|AreaColor=11599871|Color=128|PartIDLocked=T|DesignItemId=PI3A412ZHE|AllPinCount=17
|RECORD=41|OwnerIndex=28|OwnerPartId=1|Location.X=210|Location.Y=630|FontID=1|IsHidden=T|Text=Pericom|Name=Mfr_Name
|RECORD=41|OwnerIndex=28|IndexInSheet=1|OwnerPartId=1|Location.X=320|Location.Y=670|FontID=1|IsHidden=T|Text=RefDes|Name=RefDes
|RECORD=41|OwnerIndex=28|IndexInSheet=2|OwnerPartId=1|Location.X=320|Location.Y=660|FontID=1|IsHidden=T|Text=Type|Name=Type
|RECORD=2|OwnerIndex=28|OwnerPartId=1|FormalType=1|Electrical=4|PinConglomerate=58|PinLength=30|Location.X=240|Location.Y=630|Name=NC1|Designator=1|SwapIdPin=0|SwapIDPart=0Ž&Ž1|PinPropagationDelay=0.000000E+000
|RECORD=2|OwnerIndex=28|OwnerPartId=1|FormalType=1|PinConglomerate=58|PinLength=30|Location.X=240|Location.Y=620|Name=A0|Designator=2|SwapIdPin=0|SwapIDPart=0Ž&Ž2|PinPropagationDelay=0.000000E+000
|RECORD=2|OwnerIndex=28|OwnerPartId=1|FormalType=1|Electrical=4|PinConglomerate=58|PinLength=30|Location.X=240|Location.Y=610|Name=NO2|Designator=3|SwapIdPin=0|SwapIDPart=0Ž&Ž3|PinPropagationDelay=0.000000E+000
|RECORD=2|OwnerIndex=28|OwnerPartId=1|FormalType=1|Electrical=4|PinConglomerate=58|PinLength=30|Location.X=240|Location.Y=600|Name=NC2|Designator=5|SwapIdPin=0|SwapIDPart=0Ž&Ž4|PinPropagationDelay=0.000000E+000
|RECORD=2|OwnerIndex=28|OwnerPartId=1|FormalType=1|Electrical=7|PinConglomerate=58|PinLength=30|Location.X=240|Location.Y=590|Name=GND|Designator=6|SwapIdPin=0|SwapIDPart=0Ž&Ž5|PinPropagationDelay=0.000000E+000
|RECORD=2|OwnerIndex=28|OwnerPartId=1|FormalType=1|Electrical=4|PinConglomerate=58|PinLength=30|Location.X=240|Location.Y=580|Name=NO3|Designator=7|SwapIdPin=0|SwapIDPart=0Ž&Ž6|PinPropagationDelay=0.000000E+000
|RECORD=2|OwnerIndex=28|OwnerPartId=1|FormalType=1|PinConglomerate=58|PinLength=30|Location.X=240|Location.Y=570|Name=A1|Designator=10|SwapIdPin=0|SwapIDPart=0Ž&Ž7|PinPropagationDelay=0.000000E+000
|RECORD=2|OwnerIndex=28|OwnerPartId=1|FormalType=1|Electrical=2|PinConglomerate=56|PinLength=30|Location.X=400|Location.Y=540|Name=COM2|Designator=4|SwapIdPin=0|SwapIDPart=0Ž&Ž8|PinPropagationDelay=0.000000E+000
|RECORD=2|OwnerIndex=28|OwnerPartId=1|FormalType=1|Electrical=2|PinConglomerate=56|PinLength=30|Location.X=400|Location.Y=550|Name=COM3|Designator=8|SwapIdPin=0|SwapIDPart=0Ž&Ž9|PinPropagationDelay=0.000000E+000
|RECORD=2|OwnerIndex=28|OwnerPartId=1|FormalType=1|Electrical=4|PinConglomerate=56|PinLength=30|Location.X=400|Location.Y=560|Name=NC3|Designator=9|SwapIdPin=0|SwapIDPart=0Ž&Ž10|PinPropagationDelay=0.000000E+000
|RECORD=2|OwnerIndex=28|OwnerPartId=1|FormalType=1|Electrical=4|PinConglomerate=56|PinLength=30|Location.X=400|Location.Y=570|Name=NO4|Designator=11|SwapIdPin=0|SwapIDPart=0Ž&Ž11|PinPropagationDelay=0.000000E+000
|RECORD=2|OwnerIndex=28|OwnerPartId=1|FormalType=1|Electrical=2|PinConglomerate=56|PinLength=30|Location.X=400|Location.Y=580|Name=COM4|Designator=12|SwapIdPin=0|SwapIDPart=0Ž&Ž12|PinPropagationDelay=0.000000E+000
|RECORD=2|OwnerIndex=28|OwnerPartId=1|FormalType=1|Electrical=4|PinConglomerate=56|PinLength=30|Location.X=400|Location.Y=590|Name=NC4|Designator=13|SwapIdPin=0|SwapIDPart=0Ž&Ž13|PinPropagationDelay=0.000000E+000
|RECORD=2|OwnerIndex=28|OwnerPartId=1|FormalType=1|Electrical=7|PinConglomerate=56|PinLength=30|Location.X=400|Location.Y=600|Name=VCC|Designator=14|SwapIdPin=0|SwapIDPart=0Ž&Ž14|PinPropagationDelay=0.000000E+000
|RECORD=2|OwnerIndex=28|OwnerPartId=1|FormalType=1|Electrical=4|PinConglomerate=56|PinLength=30|Location.X=400|Location.Y=610|Name=NO1|Designator=15|SwapIdPin=0|SwapIDPart=0Ž&Ž15|PinPropagationDelay=0.000000E+000
|RECORD=2|OwnerIndex=28|OwnerPartId=1|FormalType=1|Electrical=2|PinConglomerate=56|PinLength=30|Location.X=400|Location.Y=620|Name=COM1|Designator=16|SwapIdPin=0|SwapIDPart=0Ž&Ž16|PinPropagationDelay=0.000000E+000
|RECORD=2|OwnerIndex=28|OwnerPartId=1|FormalType=1|Electrical=4|PinConglomerate=56|PinLength=30|Location.X=400|Location.Y=630|Name=17|Designator=17|SwapIdPin=0|SwapIDPart=0Ž&Ž17|PinPropagationDelay=0.000000E+000
|RECORD=13|OwnerIndex=28|IsNotAccesible=T|IndexInSheet=20|OwnerPartId=1|Location.X=237|Location.X_Frac=95000|Location.Y=620|Corner.X=233|Corner.X_Frac=85000|Corner.Y=622|Corner.Y_Frac=5000|LineWidth=1
|RECORD=13|OwnerIndex=28|IsNotAccesible=T|IndexInSheet=21|OwnerPartId=1|Location.X=237|Location.X_Frac=95000|Location.Y=620|Corner.X=233|Corner.X_Frac=85000|Corner.Y=617|Corner.Y_Frac=95000|LineWidth=1
|RECORD=13|OwnerIndex=28|IsNotAccesible=T|IndexInSheet=22|OwnerPartId=1|Location.X=237|Location.X_Frac=95000|Location.Y=570|Corner.X=233|Corner.X_Frac=85000|Corner.Y=572|Corner.Y_Frac=5000|LineWidth=1
|RECORD=13|OwnerIndex=28|IsNotAccesible=T|IndexInSheet=23|OwnerPartId=1|Location.X=237|Location.X_Frac=95000|Location.Y=570|Corner.X=233|Corner.X_Frac=85000|Corner.Y=567|Corner.Y_Frac=95000|LineWidth=1
|RECORD=13|OwnerIndex=28|IsNotAccesible=T|IndexInSheet=24|OwnerPartId=1|Location.X=402|Location.X_Frac=5000|Location.Y=542|Location.Y_Frac=5000|Corner.X=406|Corner.X_Frac=15000|Corner.Y=540|LineWidth=1
|RECORD=13|OwnerIndex=28|IsNotAccesible=T|IndexInSheet=25|OwnerPartId=1|Location.X=402|Location.X_Frac=5000|Location.Y=537|Location.Y_Frac=95000|Corner.X=406|Corner.X_Frac=15000|Corner.Y=540|LineWidth=1
|RECORD=13|OwnerIndex=28|IsNotAccesible=T|IndexInSheet=26|OwnerPartId=1|Location.X=402|Location.X_Frac=5000|Location.Y=552|Location.Y_Frac=5000|Corner.X=406|Corner.X_Frac=15000|Corner.Y=550|LineWidth=1
|RECORD=13|OwnerIndex=28|IsNotAccesible=T|IndexInSheet=27|OwnerPartId=1|Location.X=402|Location.X_Frac=5000|Location.Y=547|Location.Y_Frac=95000|Corner.X=406|Corner.X_Frac=15000|Corner.Y=550|LineWidth=1
|RECORD=13|OwnerIndex=28|IsNotAccesible=T|IndexInSheet=28|OwnerPartId=1|Location.X=402|Location.X_Frac=5000|Location.Y=582|Location.Y_Frac=5000|Corner.X=406|Corner.X_Frac=15000|Corner.Y=580|LineWidth=1
|RECORD=13|OwnerIndex=28|IsNotAccesible=T|IndexInSheet=29|OwnerPartId=1|Location.X=402|Location.X_Frac=5000|Location.Y=577|Location.Y_Frac=95000|Corner.X=406|Corner.X_Frac=15000|Corner.Y=580|LineWidth=1
|RECORD=13|OwnerIndex=28|IsNotAccesible=T|IndexInSheet=30|OwnerPartId=1|Location.X=402|Location.X_Frac=5000|Location.Y=622|Location.Y_Frac=5000|Corner.X=406|Corner.X_Frac=15000|Corner.Y=620|LineWidth=1
|RECORD=13|OwnerIndex=28|IsNotAccesible=T|IndexInSheet=31|OwnerPartId=1|Location.X=402|Location.X_Frac=5000|Location.Y=617|Location.Y_Frac=95000|Corner.X=406|Corner.X_Frac=15000|Corner.Y=620|LineWidth=1
|RECORD=14|OwnerIndex=28|IsNotAccesible=T|IndexInSheet=32|OwnerPartId=1|Location.X=240|Location.Y=520|Corner.X=400|Corner.Y=650|LineWidth=1|AreaColor=11599871|IsSolid=T|Transparent=T
|RECORD=34|OwnerIndex=28|IndexInSheet=-1|OwnerPartId=-1|Location.X=232|Location.X_Frac=85000|Location.Y=650|Color=8388608|FontID=1|Text=U29|Name=Designator|ReadOnlyState=1
|RECORD=41|OwnerIndex=28|IndexInSheet=-1|OwnerPartId=-1|Location.X=232|Location.X_Frac=85000|Location.Y=510|Color=8388608|FontID=1|Text=PI3A412ZHE|Name=Comment
|RECORD=44|OwnerIndex=28
|RECORD=45|OwnerIndex=81|IndexInSheet=-1|ModelName=ZH16_PER|ModelType=PCBLIB|DatafileCount=1|ModelDatafileEntity0=ZH16_PER|ModelDatafileKind0=PCBLIB|IsCurrent=T
|RECORD=46|OwnerIndex=82
|RECORD=48|OwnerIndex=82
|RECORD=4|IndexInSheet=28|OwnerPartId=-1|Location.X=630|Location.Y=880|Color=8388608|FontID=1|Text=GNSS modules need to MUX 6 signals, use 1x4 channel MUX and 1x2 channel MUX
|RECORD=1|LibReference=b4654b650e69147ec39a6b967a45e02|ComponentDescription=General Purpose Ceramic Capacitor, 0402, 100nF, 10%, X7R, 15%, 25V|PartCount=2|DisplayModeCount=1|IndexInSheet=29|OwnerPartId=-1|Location.X=570|Location.Y=700|CurrentPartId=1|LibraryPath=*|SourceLibraryName=Altium Content Vault|TargetFileName=*|AreaColor=11599871|Color=128|PartIDLocked=T|DesignItemId=CMP-2008-02519-2|AllPinCount=2
|RECORD=2|OwnerIndex=86|OwnerPartId=1|Electrical=4|PinConglomerate=49|PinLength=7|Location.X=570|Location.Y=693|Name=1|Designator=1|PinPropagationDelay=0.000000E+000
|RECORD=2|OwnerIndex=86|OwnerPartId=1|Electrical=4|PinConglomerate=51|PinLength=6|Location.X=570|Location.Y=686|Name=2|Designator=2|PinPropagationDelay=0.000000E+000
|RECORD=13|OwnerIndex=86|IsNotAccesible=T|IndexInSheet=2|OwnerPartId=1|Location.X=580|Location.Y=693|Corner.X=560|Corner.Y=693|LineWidth=1|Color=16711680
|RECORD=13|OwnerIndex=86|IsNotAccesible=T|IndexInSheet=3|OwnerPartId=1|Location.X=580|Location.Y=687|Corner.X=560|Corner.Y=687|LineWidth=1|Color=16711680
|RECORD=13|OwnerIndex=86|IsNotAccesible=T|IndexInSheet=4|OwnerPartId=1|Location.X=570|Location.Y=693|Corner.X=570|Corner.Y=696|LineWidth=1|Color=16711680
|RECORD=13|OwnerIndex=86|IsNotAccesible=T|IndexInSheet=5|OwnerPartId=1|Location.X=570|Location.Y=686|Corner.X=570|Corner.Y=685|LineWidth=1|Color=16711680
|RECORD=41|OwnerIndex=86|IndexInSheet=6|OwnerPartId=-1|Location.X=559|Location.Y=702|Color=8388608|FontID=1|IsHidden=T|Text=1|Name=Package Quantity
|RECORD=41|OwnerIndex=86|IndexInSheet=7|OwnerPartId=-1|Location.X=559|Location.Y=702|Color=8388608|FontID=1|IsHidden=T|Text=100nF|Name=Capacitance
|RECORD=41|OwnerIndex=86|IndexInSheet=8|OwnerPartId=-1|Location.X=559|Location.Y=702|Color=8388608|FontID=1|IsHidden=T|Text=-55°C|Name=Min Operating Temperature
|RECORD=41|OwnerIndex=86|IndexInSheet=9|OwnerPartId=-1|Location.X=559|Location.Y=702|Color=8388608|FontID=1|IsHidden=T|Text=25V|Name=Voltage
|RECORD=41|OwnerIndex=86|IndexInSheet=10|OwnerPartId=-1|Location.X=559|Location.Y=702|Color=8388608|FontID=1|IsHidden=T|Text=25V|Name=Voltage Rating
|RECORD=41|OwnerIndex=86|IndexInSheet=11|OwnerPartId=-1|Location.X=559|Location.Y=702|Color=8388608|FontID=1|IsHidden=T|Text=Flat|Name=Construction
|RECORD=41|OwnerIndex=86|IndexInSheet=12|OwnerPartId=-1|Location.X=559|Location.Y=702|Color=8388608|FontID=1|IsHidden=T|Text=125°C|Name=Max Operating Temperature
|RECORD=41|OwnerIndex=86|IndexInSheet=13|OwnerPartId=-1|Location.X=559|Location.Y=702|Color=8388608|FontID=1|IsHidden=T|Text=No|Name=Radiation Hardening
|RECORD=41|OwnerIndex=86|IndexInSheet=14|OwnerPartId=-1|Location.X=559|Location.Y=702|Color=8388608|FontID=1|IsHidden=T|Text=0.5mm|Name=Depth
|RECORD=41|OwnerIndex=86|IndexInSheet=15|OwnerPartId=-1|Location.X=559|Location.Y=702|Color=8388608|FontID=1|IsHidden=T|Text=0.022inch|Name=Thickness
|RECORD=41|OwnerIndex=86|IndexInSheet=16|OwnerPartId=-1|Location.X=559|Location.Y=702|Color=8388608|FontID=1|IsHidden=T|Text=25V|Name=Voltage Rating (DC)
|RECORD=41|OwnerIndex=86|IndexInSheet=17|OwnerPartId=-1|Location.X=559|Location.Y=702|Color=8388608|FontID=1|IsHidden=T|Text=2|Name=Number of Pins
|RECORD=41|OwnerIndex=86|IndexInSheet=18|OwnerPartId=-1|Location.X=559|Location.Y=702|Color=8388608|FontID=1|IsHidden=T|Text=Lead Free|Name=Lead Free
|RECORD=41|OwnerIndex=86|IndexInSheet=19|OwnerPartId=-1|Location.X=559|Location.Y=702|Color=8388608|FontID=1|IsHidden=T|Text=-|Name=Series
|RECORD=41|OwnerIndex=86|IndexInSheet=20|OwnerPartId=-1|Location.X=559|Location.Y=702|Color=8388608|FontID=1|IsHidden=T|Text=No SVHC|Name=REACH SVHC
|RECORD=41|OwnerIndex=86|IndexInSheet=21|OwnerPartId=-1|Location.X=559|Location.Y=702|Color=8388608|FontID=1|IsHidden=T|Text=1mm|Name=Length
|RECORD=41|OwnerIndex=86|IndexInSheet=22|OwnerPartId=-1|Location.X=559|Location.Y=702|Color=8388608|FontID=1|IsHidden=T|Text=X7R|Name=Dielectric
|RECORD=41|OwnerIndex=86|IndexInSheet=23|OwnerPartId=-1|Location.X=559|Location.Y=702|Color=8388608|FontID=1|IsHidden=T|Text=Yes|Name=RoHS Compliant
|RECORD=41|OwnerIndex=86|IndexInSheet=24|OwnerPartId=-1|Location.X=559|Location.Y=702|Color=8388608|FontID=1|IsHidden=T|Text=Surface Mount|Name=Mount
|RECORD=41|OwnerIndex=86|IndexInSheet=25|OwnerPartId=-1|Location.X=559|Location.Y=702|Color=8388608|FontID=1|IsHidden=T|Text=Tape and Reel|Name=Packaging
|RECORD=41|OwnerIndex=86|IndexInSheet=26|OwnerPartId=-1|Location.X=559|Location.Y=702|Color=8388608|FontID=1|IsHidden=T|Text=0402|Name=Case/Package
|RECORD=41|OwnerIndex=86|IndexInSheet=27|OwnerPartId=-1|Location.X=559|Location.Y=702|Color=8388608|FontID=1|IsHidden=T|Text=0402|Name=Case Code (Imperial)
|RECORD=41|OwnerIndex=86|IndexInSheet=28|OwnerPartId=-1|Location.X=559|Location.Y=702|Color=8388608|FontID=1|IsHidden=T|Text=SMD/SMT|Name=Termination
|RECORD=41|OwnerIndex=86|IndexInSheet=29|OwnerPartId=-1|Location.X=559|Location.Y=702|Color=8388608|FontID=1|IsHidden=T|Text=0.02inch|Name=Width
|RECORD=41|OwnerIndex=86|IndexInSheet=30|OwnerPartId=-1|Location.X=559|Location.Y=702|Color=8388608|FontID=1|IsHidden=T|Text=1005|Name=Case Code (Metric)
|RECORD=41|OwnerIndex=86|IndexInSheet=31|OwnerPartId=-1|Location.X=559|Location.Y=702|Color=8388608|FontID=1|IsHidden=T|Text=10%|Name=Tolerance
|RECORD=34|OwnerIndex=86|IndexInSheet=-1|OwnerPartId=-1|Location.X=581|Location.Y=687|Color=8388608|FontID=1|Text=C107|Name=Designator|ReadOnlyState=1
|RECORD=41|OwnerIndex=86|IndexInSheet=-1|OwnerPartId=1|Location.X=581|Location.Y=677|Color=8388608|FontID=1|Text=0.1uF_25V_0402|Name=Comment
|RECORD=44|OwnerIndex=86
|RECORD=45|OwnerIndex=123|IndexInSheet=-1|UseComponentLibrary=T|ModelName=FP-0402-L_1_0_1-W_0_5_0_1-IPC_C|ModelType=PCBLIB|DatafileCount=1|ModelDatafileEntity0=FP-0402-L_1_0_1-W_0_5_0_1-IPC_C|ModelDatafileKind0=PCBLib|IsCurrent=T|DatalinksLocked=T|DatabaseDatalinksLocked=T
|RECORD=46|OwnerIndex=124
|RECORD=48|OwnerIndex=124
|RECORD=45|OwnerIndex=123|IndexInSheet=-1|UseComponentLibrary=T|ModelName=FP-0402-L_1_0_1-W_0_5_0_1-IPC_B|ModelType=PCBLIB|DatafileCount=1|ModelDatafileEntity0=FP-0402-L_1_0_1-W_0_5_0_1-IPC_B|ModelDatafileKind0=PCBLib|DatalinksLocked=T|DatabaseDatalinksLocked=T
|RECORD=46|OwnerIndex=127
|RECORD=48|OwnerIndex=127
|RECORD=45|OwnerIndex=123|IndexInSheet=-1|UseComponentLibrary=T|ModelName=FP-0402-L_1_0_1-W_0_5_0_1-MFG|ModelType=PCBLIB|DatafileCount=1|ModelDatafileEntity0=FP-0402-L_1_0_1-W_0_5_0_1-MFG|ModelDatafileKind0=PCBLib|DatalinksLocked=T|DatabaseDatalinksLocked=T
|RECORD=46|OwnerIndex=130
|RECORD=48|OwnerIndex=130
|RECORD=45|OwnerIndex=123|IndexInSheet=-1|UseComponentLibrary=T|ModelName=FP-0402-L_1_0_1-W_0_5_0_1-IPC_A|ModelType=PCBLIB|DatafileCount=1|ModelDatafileEntity0=FP-0402-L_1_0_1-W_0_5_0_1-IPC_A|ModelDatafileKind0=PCBLib|DatalinksLocked=T|DatabaseDatalinksLocked=T
|RECORD=46|OwnerIndex=133
|RECORD=48|OwnerIndex=133
|RECORD=17|IndexInSheet=30|OwnerPartId=-1|ShowNetName=T|Location.X=570|Location.Y=750|Orientation=1|Color=128|FontID=1|Text=+3.3V
|RECORD=17|IndexInSheet=31|OwnerPartId=-1|Style=4|ShowNetName=T|Location.X=570|Location.Y=660|Orientation=3|Color=128|FontID=1|Text=GND
|RECORD=17|IndexInSheet=32|OwnerPartId=-1|ShowNetName=T|Location.X=140|Location.Y=620|Orientation=2|Color=255|FontID=1|Text=DIP_SW_GPS1_SEL|IsCrossSheetConnector=T
|RECORD=17|IndexInSheet=33|OwnerPartId=-1|Style=4|ShowNetName=T|Location.X=190|Location.Y=540|Orientation=3|Color=128|FontID=1|Text=GND
|RECORD=1|LibReference=RES|PartCount=2|DisplayModeCount=2|IndexInSheet=34|OwnerPartId=-1|Location.X=470|Location.Y=550|CurrentPartId=1|SourceLibraryName=Altium Content Vault|TargetFileName=*|AreaColor=11599871|Color=128|PartIDLocked=F|DesignItemId=CMP-2002-07709-1|AllPinCount=2
|RECORD=2|OwnerIndex=140|OwnerPartId=1|OwnerPartDisplayMode=1|FormalType=1|Electrical=4|PinConglomerate=32|PinLength=10|Location.X=490|Location.Y=540|Name=2|Designator=2|PinPropagationDelay=0.000000E+000
|RECORD=2|OwnerIndex=140|OwnerPartId=1|OwnerPartDisplayMode=1|FormalType=1|Electrical=4|PinConglomerate=34|PinLength=10|Location.X=470|Location.Y=540|Name=1|Designator=1|PinPropagationDelay=0.000000E+000
|RECORD=14|OwnerIndex=140|IsNotAccesible=T|IndexInSheet=2|OwnerPartId=1|OwnerPartDisplayMode=1|Location.X=470|Location.Y=536|Corner.X=490|Corner.Y=544|LineWidth=1|Color=16711680|AreaColor=11599871
|RECORD=2|OwnerIndex=140|OwnerPartId=1|FormalType=1|Electrical=4|PinConglomerate=32|PinLength=10|Location.X=490|Location.Y=540|Name=2|Designator=2|PinPropagationDelay=0.000000E+000
|RECORD=2|OwnerIndex=140|OwnerPartId=1|FormalType=1|Electrical=4|PinConglomerate=34|PinLength=10|Location.X=470|Location.Y=540|Name=1|Designator=1|PinPropagationDelay=0.000000E+000
|RECORD=6|OwnerIndex=140|IsNotAccesible=T|IndexInSheet=5|OwnerPartId=1|LineWidth=1|Color=16711680|LocationCount=10|X1=490|Y1=540|X2=486|Y2=540|X3=485|Y3=538|X4=483|Y4=542|X5=481|Y5=538|X6=479|Y6=542|X7=477|Y7=538|X8=475|Y8=542|X9=474|Y9=540|X10=470|Y10=540
|RECORD=41|OwnerIndex=140|IndexInSheet=6|OwnerPartId=-1|Location.X=458|Location.Y=553|Color=8388608|FontID=1|IsHidden=T|Text=Yageo / Phycomp|Name=Manufacturer
|RECORD=41|OwnerIndex=140|IndexInSheet=7|OwnerPartId=-1|Location.X=458|Location.Y=553|Color=8388608|FontID=1|IsHidden=T|Text=RC0402FR-0749R9L|Name=Part Number
|RECORD=34|OwnerIndex=140|IndexInSheet=-1|OwnerPartId=-1|Location.X=450|Location.Y=540|Color=8388608|FontID=1|Text=R152|Name=Designator|ReadOnlyState=1
|RECORD=41|OwnerIndex=140|IndexInSheet=-1|OwnerPartId=-1|Location.X=490|Location.Y=540|Color=8388608|FontID=1|Text=49.9_1%_0402|Name=Comment
|RECORD=44|OwnerIndex=140
|RECORD=45|OwnerIndex=155|IndexInSheet=-1|Description=Chip Resistor, 2-Leads, Body 1.00x0.50mm, IPC High Density|UseComponentLibrary=T|ModelName=RESC1005X40X25LL05T10|ModelType=PCBLIB|DatafileCount=1|ModelDatafileEntity0=RESC1005X40X25LL05T10|ModelDatafileKind0=PCBLib|IsCurrent=T|DatalinksLocked=T|DatabaseDatalinksLocked=T
|RECORD=46|OwnerIndex=156
|RECORD=48|OwnerIndex=156
|RECORD=41|OwnerIndex=158|IndexInSheet=-1|OwnerPartId=-1|Color=8388608|FontID=1|IsHidden=T|Text=2D|Name=Available Preview Images
|RECORD=45|OwnerIndex=155|IndexInSheet=-1|Description=Chip Resistor, 2-Leads, Body 1.00x0.50mm, IPC Low Density|UseComponentLibrary=T|ModelName=RESC1005X40X25ML05T10|ModelType=PCBLIB|DatafileCount=1|ModelDatafileEntity0=RESC1005X40X25ML05T10|ModelDatafileKind0=PCBLib|DatalinksLocked=T|DatabaseDatalinksLocked=T
|RECORD=46|OwnerIndex=160
|RECORD=48|OwnerIndex=160
|RECORD=41|OwnerIndex=162|IndexInSheet=-1|OwnerPartId=-1|Color=8388608|FontID=1|IsHidden=T|Text=2D|Name=Available Preview Images
|RECORD=45|OwnerIndex=155|IndexInSheet=-1|Description=Chip Resistor, 2-Leads, Body 1.00x0.50mm, IPC Medium Density|UseComponentLibrary=T|ModelName=RESC1005X40X25NL05T10|ModelType=PCBLIB|DatafileCount=1|ModelDatafileEntity0=RESC1005X40X25NL05T10|ModelDatafileKind0=PCBLib|DatalinksLocked=T|DatabaseDatalinksLocked=T
|RECORD=46|OwnerIndex=164
|RECORD=48|OwnerIndex=164
|RECORD=41|OwnerIndex=166|IndexInSheet=-1|OwnerPartId=-1|Color=8388608|FontID=1|IsHidden=T|Text=2D|Name=Available Preview Images
|RECORD=1|LibReference=RES|PartCount=2|DisplayModeCount=2|IndexInSheet=35|OwnerPartId=-1|Location.X=470|Location.Y=560|CurrentPartId=1|SourceLibraryName=Altium Content Vault|TargetFileName=*|AreaColor=11599871|Color=128|PartIDLocked=F|DesignItemId=CMP-2002-07709-1|AllPinCount=2
|RECORD=2|OwnerIndex=168|OwnerPartId=1|OwnerPartDisplayMode=1|FormalType=1|Electrical=4|PinConglomerate=32|PinLength=10|Location.X=490|Location.Y=550|Name=2|Designator=2|PinPropagationDelay=0.000000E+000
|RECORD=2|OwnerIndex=168|OwnerPartId=1|OwnerPartDisplayMode=1|FormalType=1|Electrical=4|PinConglomerate=34|PinLength=10|Location.X=470|Location.Y=550|Name=1|Designator=1|PinPropagationDelay=0.000000E+000
|RECORD=14|OwnerIndex=168|IsNotAccesible=T|IndexInSheet=2|OwnerPartId=1|OwnerPartDisplayMode=1|Location.X=470|Location.Y=546|Corner.X=490|Corner.Y=554|LineWidth=1|Color=16711680|AreaColor=11599871
|RECORD=2|OwnerIndex=168|OwnerPartId=1|FormalType=1|Electrical=4|PinConglomerate=32|PinLength=10|Location.X=490|Location.Y=550|Name=2|Designator=2|PinPropagationDelay=0.000000E+000
|RECORD=2|OwnerIndex=168|OwnerPartId=1|FormalType=1|Electrical=4|PinConglomerate=34|PinLength=10|Location.X=470|Location.Y=550|Name=1|Designator=1|PinPropagationDelay=0.000000E+000
|RECORD=6|OwnerIndex=168|IsNotAccesible=T|IndexInSheet=5|OwnerPartId=1|LineWidth=1|Color=16711680|LocationCount=10|X1=490|Y1=550|X2=486|Y2=550|X3=485|Y3=548|X4=483|Y4=552|X5=481|Y5=548|X6=479|Y6=552|X7=477|Y7=548|X8=475|Y8=552|X9=474|Y9=550|X10=470|Y10=550
|RECORD=41|OwnerIndex=168|IndexInSheet=6|OwnerPartId=-1|Location.X=458|Location.Y=563|Color=8388608|FontID=1|IsHidden=T|Text=Yageo / Phycomp|Name=Manufacturer
|RECORD=41|OwnerIndex=168|IndexInSheet=7|OwnerPartId=-1|Location.X=458|Location.Y=563|Color=8388608|FontID=1|IsHidden=T|Text=RC0402FR-0749R9L|Name=Part Number
|RECORD=34|OwnerIndex=168|IndexInSheet=-1|OwnerPartId=-1|Location.X=450|Location.Y=550|Color=8388608|FontID=1|Text=R150|Name=Designator|ReadOnlyState=1
|RECORD=41|OwnerIndex=168|IndexInSheet=-1|OwnerPartId=-1|Location.X=490|Location.Y=550|Color=8388608|FontID=1|Text=49.9_1%_0402|Name=Comment
|RECORD=44|OwnerIndex=168
|RECORD=45|OwnerIndex=183|IndexInSheet=-1|Description=Chip Resistor, 2-Leads, Body 1.00x0.50mm, IPC High Density|UseComponentLibrary=T|ModelName=RESC1005X40X25LL05T10|ModelType=PCBLIB|DatafileCount=1|ModelDatafileEntity0=RESC1005X40X25LL05T10|ModelDatafileKind0=PCBLib|IsCurrent=T|DatalinksLocked=T|DatabaseDatalinksLocked=T
|RECORD=46|OwnerIndex=184
|RECORD=48|OwnerIndex=184
|RECORD=41|OwnerIndex=186|IndexInSheet=-1|OwnerPartId=-1|Color=8388608|FontID=1|IsHidden=T|Text=2D|Name=Available Preview Images
|RECORD=45|OwnerIndex=183|IndexInSheet=-1|Description=Chip Resistor, 2-Leads, Body 1.00x0.50mm, IPC Low Density|UseComponentLibrary=T|ModelName=RESC1005X40X25ML05T10|ModelType=PCBLIB|DatafileCount=1|ModelDatafileEntity0=RESC1005X40X25ML05T10|ModelDatafileKind0=PCBLib|DatalinksLocked=T|DatabaseDatalinksLocked=T
|RECORD=46|OwnerIndex=188
|RECORD=48|OwnerIndex=188
|RECORD=41|OwnerIndex=190|IndexInSheet=-1|OwnerPartId=-1|Color=8388608|FontID=1|IsHidden=T|Text=2D|Name=Available Preview Images
|RECORD=45|OwnerIndex=183|IndexInSheet=-1|Description=Chip Resistor, 2-Leads, Body 1.00x0.50mm, IPC Medium Density|UseComponentLibrary=T|ModelName=RESC1005X40X25NL05T10|ModelType=PCBLIB|DatafileCount=1|ModelDatafileEntity0=RESC1005X40X25NL05T10|ModelDatafileKind0=PCBLib|DatalinksLocked=T|DatabaseDatalinksLocked=T
|RECORD=46|OwnerIndex=192
|RECORD=48|OwnerIndex=192
|RECORD=41|OwnerIndex=194|IndexInSheet=-1|OwnerPartId=-1|Color=8388608|FontID=1|IsHidden=T|Text=2D|Name=Available Preview Images
|RECORD=1|LibReference=RES|PartCount=2|DisplayModeCount=2|IndexInSheet=36|OwnerPartId=-1|Location.X=470|Location.Y=590|CurrentPartId=1|SourceLibraryName=Altium Content Vault|TargetFileName=*|AreaColor=11599871|Color=128|PartIDLocked=F|DesignItemId=CMP-2002-07709-1|AllPinCount=2
|RECORD=2|OwnerIndex=196|OwnerPartId=1|OwnerPartDisplayMode=1|FormalType=1|Electrical=4|PinConglomerate=32|PinLength=10|Location.X=490|Location.Y=580|Name=2|Designator=2|PinPropagationDelay=0.000000E+000
|RECORD=2|OwnerIndex=196|OwnerPartId=1|OwnerPartDisplayMode=1|FormalType=1|Electrical=4|PinConglomerate=34|PinLength=10|Location.X=470|Location.Y=580|Name=1|Designator=1|PinPropagationDelay=0.000000E+000
|RECORD=14|OwnerIndex=196|IsNotAccesible=T|IndexInSheet=2|OwnerPartId=1|OwnerPartDisplayMode=1|Location.X=470|Location.Y=576|Corner.X=490|Corner.Y=584|LineWidth=1|Color=16711680|AreaColor=11599871
|RECORD=2|OwnerIndex=196|OwnerPartId=1|FormalType=1|Electrical=4|PinConglomerate=32|PinLength=10|Location.X=490|Location.Y=580|Name=2|Designator=2|PinPropagationDelay=0.000000E+000
|RECORD=2|OwnerIndex=196|OwnerPartId=1|FormalType=1|Electrical=4|PinConglomerate=34|PinLength=10|Location.X=470|Location.Y=580|Name=1|Designator=1|PinPropagationDelay=0.000000E+000
|RECORD=6|OwnerIndex=196|IsNotAccesible=T|IndexInSheet=5|OwnerPartId=1|LineWidth=1|Color=16711680|LocationCount=10|X1=490|Y1=580|X2=486|Y2=580|X3=485|Y3=578|X4=483|Y4=582|X5=481|Y5=578|X6=479|Y6=582|X7=477|Y7=578|X8=475|Y8=582|X9=474|Y9=580|X10=470|Y10=580
|RECORD=41|OwnerIndex=196|IndexInSheet=6|OwnerPartId=-1|Location.X=458|Location.Y=593|Color=8388608|FontID=1|IsHidden=T|Text=Yageo / Phycomp|Name=Manufacturer
|RECORD=41|OwnerIndex=196|IndexInSheet=7|OwnerPartId=-1|Location.X=458|Location.Y=593|Color=8388608|FontID=1|IsHidden=T|Text=RC0402FR-0749R9L|Name=Part Number
|RECORD=34|OwnerIndex=196|IndexInSheet=-1|OwnerPartId=-1|Location.X=450|Location.Y=580|Color=8388608|FontID=1|Text=R147|Name=Designator|ReadOnlyState=1
|RECORD=41|OwnerIndex=196|IndexInSheet=-1|OwnerPartId=-1|Location.X=490|Location.Y=580|Color=8388608|FontID=1|Text=49.9_1%_0402|Name=Comment
|RECORD=44|OwnerIndex=196
|RECORD=45|OwnerIndex=211|IndexInSheet=-1|Description=Chip Resistor, 2-Leads, Body 1.00x0.50mm, IPC High Density|UseComponentLibrary=T|ModelName=RESC1005X40X25LL05T10|ModelType=PCBLIB|DatafileCount=1|ModelDatafileEntity0=RESC1005X40X25LL05T10|ModelDatafileKind0=PCBLib|IsCurrent=T|DatalinksLocked=T|DatabaseDatalinksLocked=T
|RECORD=46|OwnerIndex=212
|RECORD=48|OwnerIndex=212
|RECORD=41|OwnerIndex=214|IndexInSheet=-1|OwnerPartId=-1|Color=8388608|FontID=1|IsHidden=T|Text=2D|Name=Available Preview Images
|RECORD=45|OwnerIndex=211|IndexInSheet=-1|Description=Chip Resistor, 2-Leads, Body 1.00x0.50mm, IPC Low Density|UseComponentLibrary=T|ModelName=RESC1005X40X25ML05T10|ModelType=PCBLIB|DatafileCount=1|ModelDatafileEntity0=RESC1005X40X25ML05T10|ModelDatafileKind0=PCBLib|DatalinksLocked=T|DatabaseDatalinksLocked=T
|RECORD=46|OwnerIndex=216
|RECORD=48|OwnerIndex=216
|RECORD=41|OwnerIndex=218|IndexInSheet=-1|OwnerPartId=-1|Color=8388608|FontID=1|IsHidden=T|Text=2D|Name=Available Preview Images
|RECORD=45|OwnerIndex=211|IndexInSheet=-1|Description=Chip Resistor, 2-Leads, Body 1.00x0.50mm, IPC Medium Density|UseComponentLibrary=T|ModelName=RESC1005X40X25NL05T10|ModelType=PCBLIB|DatafileCount=1|ModelDatafileEntity0=RESC1005X40X25NL05T10|ModelDatafileKind0=PCBLib|DatalinksLocked=T|DatabaseDatalinksLocked=T
|RECORD=46|OwnerIndex=220
|RECORD=48|OwnerIndex=220
|RECORD=41|OwnerIndex=222|IndexInSheet=-1|OwnerPartId=-1|Color=8388608|FontID=1|IsHidden=T|Text=2D|Name=Available Preview Images
|RECORD=1|LibReference=RES|PartCount=2|DisplayModeCount=2|IndexInSheet=37|OwnerPartId=-1|Location.X=470|Location.Y=630|CurrentPartId=1|SourceLibraryName=Altium Content Vault|TargetFileName=*|AreaColor=11599871|Color=128|PartIDLocked=F|DesignItemId=CMP-2002-07709-1|AllPinCount=2
|RECORD=2|OwnerIndex=224|OwnerPartId=1|OwnerPartDisplayMode=1|FormalType=1|Electrical=4|PinConglomerate=32|PinLength=10|Location.X=490|Location.Y=620|Name=2|Designator=2|PinPropagationDelay=0.000000E+000
|RECORD=2|OwnerIndex=224|OwnerPartId=1|OwnerPartDisplayMode=1|FormalType=1|Electrical=4|PinConglomerate=34|PinLength=10|Location.X=470|Location.Y=620|Name=1|Designator=1|PinPropagationDelay=0.000000E+000
|RECORD=14|OwnerIndex=224|IsNotAccesible=T|IndexInSheet=2|OwnerPartId=1|OwnerPartDisplayMode=1|Location.X=470|Location.Y=616|Corner.X=490|Corner.Y=624|LineWidth=1|Color=16711680|AreaColor=11599871
|RECORD=2|OwnerIndex=224|OwnerPartId=1|FormalType=1|Electrical=4|PinConglomerate=32|PinLength=10|Location.X=490|Location.Y=620|Name=2|Designator=2|PinPropagationDelay=0.000000E+000
|RECORD=2|OwnerIndex=224|OwnerPartId=1|FormalType=1|Electrical=4|PinConglomerate=34|PinLength=10|Location.X=470|Location.Y=620|Name=1|Designator=1|PinPropagationDelay=0.000000E+000
|RECORD=6|OwnerIndex=224|IsNotAccesible=T|IndexInSheet=5|OwnerPartId=1|LineWidth=1|Color=16711680|LocationCount=10|X1=490|Y1=620|X2=486|Y2=620|X3=485|Y3=618|X4=483|Y4=622|X5=481|Y5=618|X6=479|Y6=622|X7=477|Y7=618|X8=475|Y8=622|X9=474|Y9=620|X10=470|Y10=620
|RECORD=41|OwnerIndex=224|IndexInSheet=6|OwnerPartId=-1|Location.X=458|Location.Y=633|Color=8388608|FontID=1|IsHidden=T|Text=Yageo / Phycomp|Name=Manufacturer
|RECORD=41|OwnerIndex=224|IndexInSheet=7|OwnerPartId=-1|Location.X=458|Location.Y=633|Color=8388608|FontID=1|IsHidden=T|Text=RC0402FR-0749R9L|Name=Part Number
|RECORD=34|OwnerIndex=224|IndexInSheet=-1|OwnerPartId=-1|Location.X=450|Location.Y=620|Color=8388608|FontID=1|Text=R144|Name=Designator|ReadOnlyState=1
|RECORD=41|OwnerIndex=224|IndexInSheet=-1|OwnerPartId=-1|Location.X=490|Location.Y=620|Color=8388608|FontID=1|Text=49.9_1%_0402|Name=Comment
|RECORD=44|OwnerIndex=224
|RECORD=45|OwnerIndex=239|IndexInSheet=-1|Description=Chip Resistor, 2-Leads, Body 1.00x0.50mm, IPC High Density|UseComponentLibrary=T|ModelName=RESC1005X40X25LL05T10|ModelType=PCBLIB|DatafileCount=1|ModelDatafileEntity0=RESC1005X40X25LL05T10|ModelDatafileKind0=PCBLib|IsCurrent=T|DatalinksLocked=T|DatabaseDatalinksLocked=T
|RECORD=46|OwnerIndex=240
|RECORD=48|OwnerIndex=240
|RECORD=41|OwnerIndex=242|IndexInSheet=-1|OwnerPartId=-1|Color=8388608|FontID=1|IsHidden=T|Text=2D|Name=Available Preview Images
|RECORD=45|OwnerIndex=239|IndexInSheet=-1|Description=Chip Resistor, 2-Leads, Body 1.00x0.50mm, IPC Low Density|UseComponentLibrary=T|ModelName=RESC1005X40X25ML05T10|ModelType=PCBLIB|DatafileCount=1|ModelDatafileEntity0=RESC1005X40X25ML05T10|ModelDatafileKind0=PCBLib|DatalinksLocked=T|DatabaseDatalinksLocked=T
|RECORD=46|OwnerIndex=244
|RECORD=48|OwnerIndex=244
|RECORD=41|OwnerIndex=246|IndexInSheet=-1|OwnerPartId=-1|Color=8388608|FontID=1|IsHidden=T|Text=2D|Name=Available Preview Images
|RECORD=45|OwnerIndex=239|IndexInSheet=-1|Description=Chip Resistor, 2-Leads, Body 1.00x0.50mm, IPC Medium Density|UseComponentLibrary=T|ModelName=RESC1005X40X25NL05T10|ModelType=PCBLIB|DatafileCount=1|ModelDatafileEntity0=RESC1005X40X25NL05T10|ModelDatafileKind0=PCBLib|DatalinksLocked=T|DatabaseDatalinksLocked=T
|RECORD=46|OwnerIndex=248
|RECORD=48|OwnerIndex=248
|RECORD=41|OwnerIndex=250|IndexInSheet=-1|OwnerPartId=-1|Color=8388608|FontID=1|IsHidden=T|Text=2D|Name=Available Preview Images
|RECORD=17|IndexInSheet=38|OwnerPartId=-1|ShowNetName=T|Location.X=420|Location.Y=470|Orientation=2|Color=255|FontID=1|Text=RCB_GPS1_TP2|IsCrossSheetConnector=T
|RECORD=17|IndexInSheet=39|OwnerPartId=-1|ShowNetName=T|Location.X=420|Location.Y=480|Orientation=2|Color=255|FontID=1|Text=RCB_GPS1_TP1|IsCrossSheetConnector=T
|RECORD=17|IndexInSheet=40|OwnerPartId=-1|ShowNetName=T|Location.X=420|Location.Y=490|Orientation=2|Color=255|FontID=1|Text=RCB_GPS1_RX|IsCrossSheetConnector=T
|RECORD=17|IndexInSheet=41|OwnerPartId=-1|ShowNetName=T|Location.X=420|Location.Y=500|Orientation=2|Color=255|FontID=1|Text=RCB_GPS1_TX|IsCrossSheetConnector=T
|RECORD=17|IndexInSheet=42|OwnerPartId=-1|ShowNetName=T|Location.X=150|Location.Y=270|Orientation=2|Color=255|FontID=1|Text=RCB_GPS1_PIN11|IsCrossSheetConnector=T
|RECORD=17|IndexInSheet=43|OwnerPartId=-1|ShowNetName=T|Location.X=150|Location.Y=230|Orientation=2|Color=255|FontID=1|Text=RCB_GPS1_PIN12|IsCrossSheetConnector=T
|RECORD=1|LibReference=RES|PartCount=2|DisplayModeCount=2|IndexInSheet=44|OwnerPartId=-1|Location.X=470|Location.Y=510|CurrentPartId=1|SourceLibraryName=Altium Content Vault|TargetFileName=*|AreaColor=11599871|Color=128|PartIDLocked=F|DesignItemId=CMP-2002-08434-1|AllPinCount=2|ComponentKindVersion2=5
|RECORD=2|OwnerIndex=258|OwnerPartId=1|OwnerPartDisplayMode=1|FormalType=1|Electrical=4|PinConglomerate=32|PinLength=10|Location.X=490|Location.Y=500|Name=2|Designator=2|PinPropagationDelay=0.000000E+000
|RECORD=2|OwnerIndex=258|OwnerPartId=1|OwnerPartDisplayMode=1|FormalType=1|Electrical=4|PinConglomerate=34|PinLength=10|Location.X=470|Location.Y=500|Name=1|Designator=1|PinPropagationDelay=0.000000E+000
|RECORD=14|OwnerIndex=258|IsNotAccesible=T|IndexInSheet=2|OwnerPartId=1|OwnerPartDisplayMode=1|Location.X=470|Location.Y=496|Corner.X=490|Corner.Y=504|LineWidth=1|Color=16711680|AreaColor=11599871
|RECORD=2|OwnerIndex=258|OwnerPartId=1|FormalType=1|Electrical=4|PinConglomerate=32|PinLength=10|Location.X=490|Location.Y=500|Name=2|Designator=2|PinPropagationDelay=0.000000E+000
|RECORD=2|OwnerIndex=258|OwnerPartId=1|FormalType=1|Electrical=4|PinConglomerate=34|PinLength=10|Location.X=470|Location.Y=500|Name=1|Designator=1|PinPropagationDelay=0.000000E+000
|RECORD=6|OwnerIndex=258|IsNotAccesible=T|IndexInSheet=5|OwnerPartId=1|LineWidth=1|Color=16711680|LocationCount=10|X1=490|Y1=500|X2=486|Y2=500|X3=485|Y3=498|X4=483|Y4=502|X5=481|Y5=498|X6=479|Y6=502|X7=477|Y7=498|X8=475|Y8=502|X9=474|Y9=500|X10=470|Y10=500
|RECORD=41|OwnerIndex=258|IndexInSheet=6|OwnerPartId=-1|Location.X=458|Location.Y=513|Color=8388608|FontID=1|IsHidden=T|Text=CRCW040227R0FKED|Name=Part Number
|RECORD=41|OwnerIndex=258|IndexInSheet=7|OwnerPartId=-1|Location.X=458|Location.Y=513|Color=8388608|FontID=1|IsHidden=T|Text=Vishay Dale|Name=Manufacturer
|RECORD=34|OwnerIndex=258|IndexInSheet=-1|OwnerPartId=-1|Location.X=450|Location.Y=500|Color=8388608|FontID=1|Text=R155|Name=Designator|ReadOnlyState=1
|RECORD=41|OwnerIndex=258|IndexInSheet=-1|OwnerPartId=-1|Location.X=470|Location.Y=500|Color=8388608|FontID=1|Text=DNI_27_1%_0402|Name=Comment
|RECORD=44|OwnerIndex=258
|RECORD=45|OwnerIndex=273|IndexInSheet=-1|Description=Chip Resistor, 2-Leads, Body 1.00x0.50mm, IPC Medium Density|UseComponentLibrary=T|ModelName=RESC1005X40X25NL05T05|ModelType=PCBLIB|DatafileCount=1|ModelDatafileEntity0=RESC1005X40X25NL05T05|ModelDatafileKind0=PCBLib|IsCurrent=T|DatalinksLocked=T|DatabaseDatalinksLocked=T
|RECORD=46|OwnerIndex=274
|RECORD=48|OwnerIndex=274
|RECORD=41|OwnerIndex=276|IndexInSheet=-1|OwnerPartId=-1|Color=8388608|FontID=1|IsHidden=T|Text=2D|Name=Available Preview Images
|RECORD=45|OwnerIndex=273|IndexInSheet=-1|Description=Chip Resistor, 2-Leads, Body 1.00x0.50mm, IPC High Density|UseComponentLibrary=T|ModelName=RESC1005X40X25LL05T05|ModelType=PCBLIB|DatafileCount=1|ModelDatafileEntity0=RESC1005X40X25LL05T05|ModelDatafileKind0=PCBLib|DatalinksLocked=T|DatabaseDatalinksLocked=T
|RECORD=46|OwnerIndex=278
|RECORD=48|OwnerIndex=278
|RECORD=41|OwnerIndex=280|IndexInSheet=-1|OwnerPartId=-1|Color=8388608|FontID=1|IsHidden=T|Text=2D|Name=Available Preview Images
|RECORD=45|OwnerIndex=273|IndexInSheet=-1|Description=Chip Resistor, 2-Leads, Body 1.00x0.50mm, IPC Low Density|UseComponentLibrary=T|ModelName=RESC1005X40X25ML05T05|ModelType=PCBLIB|DatafileCount=1|ModelDatafileEntity0=RESC1005X40X25ML05T05|ModelDatafileKind0=PCBLib|DatalinksLocked=T|DatabaseDatalinksLocked=T
|RECORD=46|OwnerIndex=282
|RECORD=48|OwnerIndex=282
|RECORD=41|OwnerIndex=284|IndexInSheet=-1|OwnerPartId=-1|Color=8388608|FontID=1|IsHidden=T|Text=2D|Name=Available Preview Images
|RECORD=1|LibReference=RES|PartCount=2|DisplayModeCount=2|IndexInSheet=45|OwnerPartId=-1|Location.X=470|Location.Y=500|CurrentPartId=1|SourceLibraryName=Altium Content Vault|TargetFileName=*|AreaColor=11599871|Color=128|PartIDLocked=F|DesignItemId=CMP-2002-08434-1|AllPinCount=2|ComponentKindVersion2=5
|RECORD=2|OwnerIndex=286|OwnerPartId=1|OwnerPartDisplayMode=1|FormalType=1|Electrical=4|PinConglomerate=32|PinLength=10|Location.X=490|Location.Y=490|Name=2|Designator=2|PinPropagationDelay=0.000000E+000
|RECORD=2|OwnerIndex=286|OwnerPartId=1|OwnerPartDisplayMode=1|FormalType=1|Electrical=4|PinConglomerate=34|PinLength=10|Location.X=470|Location.Y=490|Name=1|Designator=1|PinPropagationDelay=0.000000E+000
|RECORD=14|OwnerIndex=286|IsNotAccesible=T|IndexInSheet=2|OwnerPartId=1|OwnerPartDisplayMode=1|Location.X=470|Location.Y=486|Corner.X=490|Corner.Y=494|LineWidth=1|Color=16711680|AreaColor=11599871
|RECORD=2|OwnerIndex=286|OwnerPartId=1|FormalType=1|Electrical=4|PinConglomerate=32|PinLength=10|Location.X=490|Location.Y=490|Name=2|Designator=2|PinPropagationDelay=0.000000E+000
|RECORD=2|OwnerIndex=286|OwnerPartId=1|FormalType=1|Electrical=4|PinConglomerate=34|PinLength=10|Location.X=470|Location.Y=490|Name=1|Designator=1|PinPropagationDelay=0.000000E+000
|RECORD=6|OwnerIndex=286|IsNotAccesible=T|IndexInSheet=5|OwnerPartId=1|LineWidth=1|Color=16711680|LocationCount=10|X1=490|Y1=490|X2=486|Y2=490|X3=485|Y3=488|X4=483|Y4=492|X5=481|Y5=488|X6=479|Y6=492|X7=477|Y7=488|X8=475|Y8=492|X9=474|Y9=490|X10=470|Y10=490
|RECORD=41|OwnerIndex=286|IndexInSheet=6|OwnerPartId=-1|Location.X=458|Location.Y=503|Color=8388608|FontID=1|IsHidden=T|Text=CRCW040227R0FKED|Name=Part Number
|RECORD=41|OwnerIndex=286|IndexInSheet=7|OwnerPartId=-1|Location.X=458|Location.Y=503|Color=8388608|FontID=1|IsHidden=T|Text=Vishay Dale|Name=Manufacturer
|RECORD=34|OwnerIndex=286|IndexInSheet=-1|OwnerPartId=-1|Location.X=450|Location.Y=490|Color=8388608|FontID=1|Text=R157|Name=Designator|ReadOnlyState=1
|RECORD=41|OwnerIndex=286|IndexInSheet=-1|OwnerPartId=-1|Location.X=470|Location.Y=490|Color=8388608|FontID=1|Text=DNI_27_1%_0402|Name=Comment
|RECORD=44|OwnerIndex=286
|RECORD=45|OwnerIndex=301|IndexInSheet=-1|Description=Chip Resistor, 2-Leads, Body 1.00x0.50mm, IPC Medium Density|UseComponentLibrary=T|ModelName=RESC1005X40X25NL05T05|ModelType=PCBLIB|DatafileCount=1|ModelDatafileEntity0=RESC1005X40X25NL05T05|ModelDatafileKind0=PCBLib|IsCurrent=T|DatalinksLocked=T|DatabaseDatalinksLocked=T
|RECORD=46|OwnerIndex=302
|RECORD=48|OwnerIndex=302
|RECORD=41|OwnerIndex=304|IndexInSheet=-1|OwnerPartId=-1|Color=8388608|FontID=1|IsHidden=T|Text=2D|Name=Available Preview Images
|RECORD=45|OwnerIndex=301|IndexInSheet=-1|Description=Chip Resistor, 2-Leads, Body 1.00x0.50mm, IPC High Density|UseComponentLibrary=T|ModelName=RESC1005X40X25LL05T05|ModelType=PCBLIB|DatafileCount=1|ModelDatafileEntity0=RESC1005X40X25LL05T05|ModelDatafileKind0=PCBLib|DatalinksLocked=T|DatabaseDatalinksLocked=T
|RECORD=46|OwnerIndex=306
|RECORD=48|OwnerIndex=306
|RECORD=41|OwnerIndex=308|IndexInSheet=-1|OwnerPartId=-1|Color=8388608|FontID=1|IsHidden=T|Text=2D|Name=Available Preview Images
|RECORD=45|OwnerIndex=301|IndexInSheet=-1|Description=Chip Resistor, 2-Leads, Body 1.00x0.50mm, IPC Low Density|UseComponentLibrary=T|ModelName=RESC1005X40X25ML05T05|ModelType=PCBLIB|DatafileCount=1|ModelDatafileEntity0=RESC1005X40X25ML05T05|ModelDatafileKind0=PCBLib|DatalinksLocked=T|DatabaseDatalinksLocked=T
|RECORD=46|OwnerIndex=310
|RECORD=48|OwnerIndex=310
|RECORD=41|OwnerIndex=312|IndexInSheet=-1|OwnerPartId=-1|Color=8388608|FontID=1|IsHidden=T|Text=2D|Name=Available Preview Images
|RECORD=1|LibReference=RES|PartCount=2|DisplayModeCount=2|IndexInSheet=46|OwnerPartId=-1|Location.X=470|Location.Y=480|CurrentPartId=1|SourceLibraryName=Altium Content Vault|TargetFileName=*|AreaColor=11599871|Color=128|PartIDLocked=F|DesignItemId=CMP-2002-08434-1|AllPinCount=2|ComponentKindVersion2=5
|RECORD=2|OwnerIndex=314|OwnerPartId=1|OwnerPartDisplayMode=1|FormalType=1|Electrical=4|PinConglomerate=32|PinLength=10|Location.X=490|Location.Y=470|Name=2|Designator=2|PinPropagationDelay=0.000000E+000
|RECORD=2|OwnerIndex=314|OwnerPartId=1|OwnerPartDisplayMode=1|FormalType=1|Electrical=4|PinConglomerate=34|PinLength=10|Location.X=470|Location.Y=470|Name=1|Designator=1|PinPropagationDelay=0.000000E+000
|RECORD=14|OwnerIndex=314|IsNotAccesible=T|IndexInSheet=2|OwnerPartId=1|OwnerPartDisplayMode=1|Location.X=470|Location.Y=466|Corner.X=490|Corner.Y=474|LineWidth=1|Color=16711680|AreaColor=11599871
|RECORD=2|OwnerIndex=314|OwnerPartId=1|FormalType=1|Electrical=4|PinConglomerate=32|PinLength=10|Location.X=490|Location.Y=470|Name=2|Designator=2|PinPropagationDelay=0.000000E+000
|RECORD=2|OwnerIndex=314|OwnerPartId=1|FormalType=1|Electrical=4|PinConglomerate=34|PinLength=10|Location.X=470|Location.Y=470|Name=1|Designator=1|PinPropagationDelay=0.000000E+000
|RECORD=6|OwnerIndex=314|IsNotAccesible=T|IndexInSheet=5|OwnerPartId=1|LineWidth=1|Color=16711680|LocationCount=10|X1=490|Y1=470|X2=486|Y2=470|X3=485|Y3=468|X4=483|Y4=472|X5=481|Y5=468|X6=479|Y6=472|X7=477|Y7=468|X8=475|Y8=472|X9=474|Y9=470|X10=470|Y10=470
|RECORD=41|OwnerIndex=314|IndexInSheet=6|OwnerPartId=-1|Location.X=458|Location.Y=483|Color=8388608|FontID=1|IsHidden=T|Text=CRCW040227R0FKED|Name=Part Number
|RECORD=41|OwnerIndex=314|IndexInSheet=7|OwnerPartId=-1|Location.X=458|Location.Y=483|Color=8388608|FontID=1|IsHidden=T|Text=Vishay Dale|Name=Manufacturer
|RECORD=34|OwnerIndex=314|IndexInSheet=-1|OwnerPartId=-1|Location.X=450|Location.Y=470|Color=8388608|FontID=1|Text=R161|Name=Designator|ReadOnlyState=1
|RECORD=41|OwnerIndex=314|IndexInSheet=-1|OwnerPartId=-1|Location.X=470|Location.Y=470|Color=8388608|FontID=1|Text=DNI_27_1%_0402|Name=Comment
|RECORD=44|OwnerIndex=314
|RECORD=45|OwnerIndex=329|IndexInSheet=-1|Description=Chip Resistor, 2-Leads, Body 1.00x0.50mm, IPC Medium Density|UseComponentLibrary=T|ModelName=RESC1005X40X25NL05T05|ModelType=PCBLIB|DatafileCount=1|ModelDatafileEntity0=RESC1005X40X25NL05T05|ModelDatafileKind0=PCBLib|IsCurrent=T|DatalinksLocked=T|DatabaseDatalinksLocked=T
|RECORD=46|OwnerIndex=330
|RECORD=48|OwnerIndex=330
|RECORD=41|OwnerIndex=332|IndexInSheet=-1|OwnerPartId=-1|Color=8388608|FontID=1|IsHidden=T|Text=2D|Name=Available Preview Images
|RECORD=45|OwnerIndex=329|IndexInSheet=-1|Description=Chip Resistor, 2-Leads, Body 1.00x0.50mm, IPC High Density|UseComponentLibrary=T|ModelName=RESC1005X40X25LL05T05|ModelType=PCBLIB|DatafileCount=1|ModelDatafileEntity0=RESC1005X40X25LL05T05|ModelDatafileKind0=PCBLib|DatalinksLocked=T|DatabaseDatalinksLocked=T
|RECORD=46|OwnerIndex=334
|RECORD=48|OwnerIndex=334
|RECORD=41|OwnerIndex=336|IndexInSheet=-1|OwnerPartId=-1|Color=8388608|FontID=1|IsHidden=T|Text=2D|Name=Available Preview Images
|RECORD=45|OwnerIndex=329|IndexInSheet=-1|Description=Chip Resistor, 2-Leads, Body 1.00x0.50mm, IPC Low Density|UseComponentLibrary=T|ModelName=RESC1005X40X25ML05T05|ModelType=PCBLIB|DatafileCount=1|ModelDatafileEntity0=RESC1005X40X25ML05T05|ModelDatafileKind0=PCBLib|DatalinksLocked=T|DatabaseDatalinksLocked=T
|RECORD=46|OwnerIndex=338
|RECORD=48|OwnerIndex=338
|RECORD=41|OwnerIndex=340|IndexInSheet=-1|OwnerPartId=-1|Color=8388608|FontID=1|IsHidden=T|Text=2D|Name=Available Preview Images
|RECORD=1|LibReference=RES|PartCount=2|DisplayModeCount=2|IndexInSheet=47|OwnerPartId=-1|Location.X=470|Location.Y=490|CurrentPartId=1|SourceLibraryName=Altium Content Vault|TargetFileName=*|AreaColor=11599871|Color=128|PartIDLocked=F|DesignItemId=CMP-2002-08434-1|AllPinCount=2|ComponentKindVersion2=5
|RECORD=2|OwnerIndex=342|OwnerPartId=1|OwnerPartDisplayMode=1|FormalType=1|Electrical=4|PinConglomerate=32|PinLength=10|Location.X=490|Location.Y=480|Name=2|Designator=2|PinPropagationDelay=0.000000E+000
|RECORD=2|OwnerIndex=342|OwnerPartId=1|OwnerPartDisplayMode=1|FormalType=1|Electrical=4|PinConglomerate=34|PinLength=10|Location.X=470|Location.Y=480|Name=1|Designator=1|PinPropagationDelay=0.000000E+000
|RECORD=14|OwnerIndex=342|IsNotAccesible=T|IndexInSheet=2|OwnerPartId=1|OwnerPartDisplayMode=1|Location.X=470|Location.Y=476|Corner.X=490|Corner.Y=484|LineWidth=1|Color=16711680|AreaColor=11599871
|RECORD=2|OwnerIndex=342|OwnerPartId=1|FormalType=1|Electrical=4|PinConglomerate=32|PinLength=10|Location.X=490|Location.Y=480|Name=2|Designator=2|PinPropagationDelay=0.000000E+000
|RECORD=2|OwnerIndex=342|OwnerPartId=1|FormalType=1|Electrical=4|PinConglomerate=34|PinLength=10|Location.X=470|Location.Y=480|Name=1|Designator=1|PinPropagationDelay=0.000000E+000
|RECORD=6|OwnerIndex=342|IsNotAccesible=T|IndexInSheet=5|OwnerPartId=1|LineWidth=1|Color=16711680|LocationCount=10|X1=490|Y1=480|X2=486|Y2=480|X3=485|Y3=478|X4=483|Y4=482|X5=481|Y5=478|X6=479|Y6=482|X7=477|Y7=478|X8=475|Y8=482|X9=474|Y9=480|X10=470|Y10=480
|RECORD=41|OwnerIndex=342|IndexInSheet=6|OwnerPartId=-1|Location.X=458|Location.Y=493|Color=8388608|FontID=1|IsHidden=T|Text=CRCW040227R0FKED|Name=Part Number
|RECORD=41|OwnerIndex=342|IndexInSheet=7|OwnerPartId=-1|Location.X=458|Location.Y=493|Color=8388608|FontID=1|IsHidden=T|Text=Vishay Dale|Name=Manufacturer
|RECORD=34|OwnerIndex=342|IndexInSheet=-1|OwnerPartId=-1|Location.X=450|Location.Y=480|Color=8388608|FontID=1|Text=R159|Name=Designator|ReadOnlyState=1
|RECORD=41|OwnerIndex=342|IndexInSheet=-1|OwnerPartId=-1|Location.X=470|Location.Y=480|Color=8388608|FontID=1|Text=DNI_27_1%_0402|Name=Comment
|RECORD=44|OwnerIndex=342
|RECORD=45|OwnerIndex=357|IndexInSheet=-1|Description=Chip Resistor, 2-Leads, Body 1.00x0.50mm, IPC Medium Density|UseComponentLibrary=T|ModelName=RESC1005X40X25NL05T05|ModelType=PCBLIB|DatafileCount=1|ModelDatafileEntity0=RESC1005X40X25NL05T05|ModelDatafileKind0=PCBLib|IsCurrent=T|DatalinksLocked=T|DatabaseDatalinksLocked=T
|RECORD=46|OwnerIndex=358
|RECORD=48|OwnerIndex=358
|RECORD=41|OwnerIndex=360|IndexInSheet=-1|OwnerPartId=-1|Color=8388608|FontID=1|IsHidden=T|Text=2D|Name=Available Preview Images
|RECORD=45|OwnerIndex=357|IndexInSheet=-1|Description=Chip Resistor, 2-Leads, Body 1.00x0.50mm, IPC High Density|UseComponentLibrary=T|ModelName=RESC1005X40X25LL05T05|ModelType=PCBLIB|DatafileCount=1|ModelDatafileEntity0=RESC1005X40X25LL05T05|ModelDatafileKind0=PCBLib|DatalinksLocked=T|DatabaseDatalinksLocked=T
|RECORD=46|OwnerIndex=362
|RECORD=48|OwnerIndex=362
|RECORD=41|OwnerIndex=364|IndexInSheet=-1|OwnerPartId=-1|Color=8388608|FontID=1|IsHidden=T|Text=2D|Name=Available Preview Images
|RECORD=45|OwnerIndex=357|IndexInSheet=-1|Description=Chip Resistor, 2-Leads, Body 1.00x0.50mm, IPC Low Density|UseComponentLibrary=T|ModelName=RESC1005X40X25ML05T05|ModelType=PCBLIB|DatafileCount=1|ModelDatafileEntity0=RESC1005X40X25ML05T05|ModelDatafileKind0=PCBLib|DatalinksLocked=T|DatabaseDatalinksLocked=T
|RECORD=46|OwnerIndex=366
|RECORD=48|OwnerIndex=366
|RECORD=41|OwnerIndex=368|IndexInSheet=-1|OwnerPartId=-1|Color=8388608|FontID=1|IsHidden=T|Text=2D|Name=Available Preview Images
|RECORD=4|IndexInSheet=48|OwnerPartId=-1|Location.X=690|Location.Y=860|Color=8388608|FontID=1|Text=RST is just tied to both, and I2C and IRQ is tied to both
|RECORD=1|LibReference=12a319ab100cd6cfe745e35972674f5|ComponentDescription=IC SWITCH SPDT DUAL 12UQFN|PartCount=2|DisplayModeCount=1|IndexInSheet=49|OwnerPartId=-1|Location.X=240|Location.Y=290|CurrentPartId=1|LibraryPath=*|SourceLibraryName=Altium Content Vault|TargetFileName=*|AreaColor=11599871|Color=128|PartIDLocked=T|DesignItemId=CMP-04892-000114-1|AllPinCount=12
|RECORD=14|OwnerIndex=371|IsNotAccesible=T|OwnerPartId=1|Location.X=260|Location.Y=130|Corner.X=360|Corner.Y=300|LineWidth=1|Color=128|AreaColor=11599871|IsSolid=T
|RECORD=2|OwnerIndex=371|OwnerPartId=1|Electrical=7|PinConglomerate=58|PinLength=20|Location.X=260|Location.Y=290|Name=VCC|Designator=9|PinName_PositionConglomerate=16|Name_CustomFontID=1|PinDesignator_PositionConglomerate=16|Designator_CustomFontID=1|PinPropagationDelay=0.000000E+000
|RECORD=2|OwnerIndex=371|OwnerPartId=1|PinConglomerate=58|PinLength=20|Location.X=260|Location.Y=190|Name=SEL1|Designator=1|PinName_PositionConglomerate=16|Name_CustomFontID=1|PinDesignator_PositionConglomerate=16|Designator_CustomFontID=1|PinPropagationDelay=0.000000E+000
|RECORD=2|OwnerIndex=371|OwnerPartId=1|PinConglomerate=58|PinLength=20|Location.X=260|Location.Y=180|Name=SEL2|Designator=5|PinName_PositionConglomerate=16|Name_CustomFontID=1|PinDesignator_PositionConglomerate=16|Designator_CustomFontID=1|PinPropagationDelay=0.000000E+000
|RECORD=2|OwnerIndex=371|OwnerPartId=1|Electrical=4|PinConglomerate=58|PinLength=20|Location.X=260|Location.Y=250|Name=NO1|Designator=2|PinName_PositionConglomerate=16|Name_CustomFontID=1|PinDesignator_PositionConglomerate=16|Designator_CustomFontID=1|PinPropagationDelay=0.000000E+000
|RECORD=2|OwnerIndex=371|OwnerPartId=1|Electrical=4|PinConglomerate=58|PinLength=20|Location.X=260|Location.Y=210|Name=NO2|Designator=4|PinName_PositionConglomerate=16|Name_CustomFontID=1|PinDesignator_PositionConglomerate=16|Designator_CustomFontID=1|PinPropagationDelay=0.000000E+000
|RECORD=2|OwnerIndex=371|OwnerPartId=1|Electrical=4|PinConglomerate=56|PinLength=20|Location.X=360|Location.Y=270|Name=COM1|Designator=11|PinName_PositionConglomerate=16|Name_CustomFontID=1|PinDesignator_PositionConglomerate=16|Designator_CustomFontID=1|PinPropagationDelay=0.000000E+000
|RECORD=2|OwnerIndex=371|OwnerPartId=1|Electrical=4|PinConglomerate=56|PinLength=20|Location.X=360|Location.Y=230|Name=COM2|Designator=7|PinName_PositionConglomerate=16|Name_CustomFontID=1|PinDesignator_PositionConglomerate=16|Designator_CustomFontID=1|PinPropagationDelay=0.000000E+000
|RECORD=2|OwnerIndex=371|OwnerPartId=1|Electrical=3|PinConglomerate=58|PinLength=20|Location.X=260|Location.Y=140|Name=F\L\T\|Designator=12|PinName_PositionConglomerate=16|Name_CustomFontID=1|PinDesignator_PositionConglomerate=16|Designator_CustomFontID=1|PinPropagationDelay=0.000000E+000
|RECORD=2|OwnerIndex=371|OwnerPartId=1|PinConglomerate=58|PinLength=20|Location.X=260|Location.Y=160|Name=O\E\|Designator=6|PinName_PositionConglomerate=16|Name_CustomFontID=1|PinDesignator_PositionConglomerate=16|Designator_CustomFontID=1|PinPropagationDelay=0.000000E+000
|RECORD=2|OwnerIndex=371|OwnerPartId=1|Electrical=4|PinConglomerate=58|PinLength=20|Location.X=260|Location.Y=270|Name=NC1|Designator=10|PinName_PositionConglomerate=16|Name_CustomFontID=1|PinDesignator_PositionConglomerate=16|Designator_CustomFontID=1|PinPropagationDelay=0.000000E+000
|RECORD=2|OwnerIndex=371|OwnerPartId=1|Electrical=4|PinConglomerate=58|PinLength=20|Location.X=260|Location.Y=230|Name=NC2|Designator=8|PinName_PositionConglomerate=16|Name_CustomFontID=1|PinDesignator_PositionConglomerate=16|Designator_CustomFontID=1|PinPropagationDelay=0.000000E+000
|RECORD=2|OwnerIndex=371|OwnerPartId=1|Electrical=7|PinConglomerate=56|PinLength=20|Location.X=360|Location.Y=140|Name=GND|Designator=3|PinName_PositionConglomerate=16|Name_CustomFontID=1|PinDesignator_PositionConglomerate=16|Designator_CustomFontID=1|PinPropagationDelay=0.000000E+000
|RECORD=41|OwnerIndex=371|IndexInSheet=13|OwnerPartId=-1|Location.X=238|Location.Y=300|Color=8388608|FontID=1|IsHidden=T|Text=12|Name=Number of Pins
|RECORD=41|OwnerIndex=371|IndexInSheet=14|OwnerPartId=-1|Location.X=238|Location.Y=300|Color=8388608|FontID=1|IsHidden=T|Text=2|Name=Number of Circuits
|RECORD=41|OwnerIndex=371|IndexInSheet=15|OwnerPartId=-1|Location.X=238|Location.Y=300|Color=8388608|FontID=1|IsHidden=T|Text=-40°C|Name=Min Operating Temperature
|RECORD=41|OwnerIndex=371|IndexInSheet=16|OwnerPartId=-1|Location.X=238|Location.Y=300|Color=8388608|FontID=1|IsHidden=T|Text=Yes|Name=RoHS Compliant
|RECORD=41|OwnerIndex=371|IndexInSheet=17|OwnerPartId=-1|Location.X=238|Location.Y=300|Color=8388608|FontID=1|IsHidden=T|Text=1.2GHz|Name=-3db Bandwidth
|RECORD=41|OwnerIndex=371|IndexInSheet=18|OwnerPartId=-1|Location.X=238|Location.Y=300|Color=8388608|FontID=1|IsHidden=T|Text=125°C|Name=Max Operating Temperature
|RECORD=41|OwnerIndex=371|IndexInSheet=19|OwnerPartId=-1|Location.X=238|Location.Y=300|Color=8388608|FontID=1|IsHidden=T|Text=2|Name=Number of Channels
|RECORD=41|OwnerIndex=371|IndexInSheet=20|OwnerPartId=-1|Location.X=238|Location.Y=300|Color=8388608|FontID=1|IsHidden=T|Text=18R|Name=On-State Resistance
|RECORD=41|OwnerIndex=371|IndexInSheet=21|OwnerPartId=-1|Location.X=238|Location.Y=300|Color=8388608|FontID=1|IsHidden=T|Text=Tape and Reel|Name=Packaging
|RECORD=34|OwnerIndex=371|IndexInSheet=-1|OwnerPartId=-1|Location.X=260|Location.Y=300|Color=8388608|FontID=1|Text=U31|Name=Designator|ReadOnlyState=1
|RECORD=41|OwnerIndex=371|IndexInSheet=-1|OwnerPartId=1|Location.X=260|Location.Y=120|Color=8388608|FontID=1|Text=TMUX1072RUTR|Name=Comment
|RECORD=44|OwnerIndex=371
|RECORD=45|OwnerIndex=408|IndexInSheet=-1|UseComponentLibrary=T|ModelName=FP-RUT0012A-MFG|ModelType=PCBLIB|DatafileCount=1|ModelDatafileEntity0=FP-RUT0012A-MFG|ModelDatafileKind0=PCBLib|IsCurrent=T|DatalinksLocked=T|DatabaseDatalinksLocked=T
|RECORD=46|OwnerIndex=409
|RECORD=48|OwnerIndex=409
|RECORD=17|IndexInSheet=50|OwnerPartId=-1|Style=4|ShowNetName=T|Location.X=220|Location.Y=130|Orientation=3|Color=128|FontID=1|Text=GND
|RECORD=1|LibReference=b4654b650e69147ec39a6b967a45e02|ComponentDescription=General Purpose Ceramic Capacitor, 0402, 100nF, 10%, X7R, 15%, 25V|PartCount=2|DisplayModeCount=1|IndexInSheet=51|OwnerPartId=-1|Location.X=180|Location.Y=320|CurrentPartId=1|LibraryPath=*|SourceLibraryName=Altium Content Vault|TargetFileName=*|AreaColor=11599871|Color=128|PartIDLocked=T|DesignItemId=CMP-2008-02519-2|AllPinCount=2
|RECORD=2|OwnerIndex=413|OwnerPartId=1|Electrical=4|PinConglomerate=49|PinLength=7|Location.X=180|Location.Y=313|Name=1|Designator=1|PinPropagationDelay=0.000000E+000
|RECORD=2|OwnerIndex=413|OwnerPartId=1|Electrical=4|PinConglomerate=51|PinLength=6|Location.X=180|Location.Y=306|Name=2|Designator=2|PinPropagationDelay=0.000000E+000
|RECORD=13|OwnerIndex=413|IsNotAccesible=T|IndexInSheet=2|OwnerPartId=1|Location.X=190|Location.Y=313|Corner.X=170|Corner.Y=313|LineWidth=1|Color=16711680
|RECORD=13|OwnerIndex=413|IsNotAccesible=T|IndexInSheet=3|OwnerPartId=1|Location.X=190|Location.Y=307|Corner.X=170|Corner.Y=307|LineWidth=1|Color=16711680
|RECORD=13|OwnerIndex=413|IsNotAccesible=T|IndexInSheet=4|OwnerPartId=1|Location.X=180|Location.Y=313|Corner.X=180|Corner.Y=316|LineWidth=1|Color=16711680
|RECORD=13|OwnerIndex=413|IsNotAccesible=T|IndexInSheet=5|OwnerPartId=1|Location.X=180|Location.Y=306|Corner.X=180|Corner.Y=305|LineWidth=1|Color=16711680
|RECORD=41|OwnerIndex=413|IndexInSheet=6|OwnerPartId=-1|Location.X=169|Location.Y=322|Color=8388608|FontID=1|IsHidden=T|Text=1|Name=Package Quantity
|RECORD=41|OwnerIndex=413|IndexInSheet=7|OwnerPartId=-1|Location.X=169|Location.Y=322|Color=8388608|FontID=1|IsHidden=T|Text=100nF|Name=Capacitance
|RECORD=41|OwnerIndex=413|IndexInSheet=8|OwnerPartId=-1|Location.X=169|Location.Y=322|Color=8388608|FontID=1|IsHidden=T|Text=-55°C|Name=Min Operating Temperature
|RECORD=41|OwnerIndex=413|IndexInSheet=9|OwnerPartId=-1|Location.X=169|Location.Y=322|Color=8388608|FontID=1|IsHidden=T|Text=25V|Name=Voltage
|RECORD=41|OwnerIndex=413|IndexInSheet=10|OwnerPartId=-1|Location.X=169|Location.Y=322|Color=8388608|FontID=1|IsHidden=T|Text=25V|Name=Voltage Rating
|RECORD=41|OwnerIndex=413|IndexInSheet=11|OwnerPartId=-1|Location.X=169|Location.Y=322|Color=8388608|FontID=1|IsHidden=T|Text=Flat|Name=Construction
|RECORD=41|OwnerIndex=413|IndexInSheet=12|OwnerPartId=-1|Location.X=169|Location.Y=322|Color=8388608|FontID=1|IsHidden=T|Text=125°C|Name=Max Operating Temperature
|RECORD=41|OwnerIndex=413|IndexInSheet=13|OwnerPartId=-1|Location.X=169|Location.Y=322|Color=8388608|FontID=1|IsHidden=T|Text=No|Name=Radiation Hardening
|RECORD=41|OwnerIndex=413|IndexInSheet=14|OwnerPartId=-1|Location.X=169|Location.Y=322|Color=8388608|FontID=1|IsHidden=T|Text=0.5mm|Name=Depth
|RECORD=41|OwnerIndex=413|IndexInSheet=15|OwnerPartId=-1|Location.X=169|Location.Y=322|Color=8388608|FontID=1|IsHidden=T|Text=0.022inch|Name=Thickness
|RECORD=41|OwnerIndex=413|IndexInSheet=16|OwnerPartId=-1|Location.X=169|Location.Y=322|Color=8388608|FontID=1|IsHidden=T|Text=25V|Name=Voltage Rating (DC)
|RECORD=41|OwnerIndex=413|IndexInSheet=17|OwnerPartId=-1|Location.X=169|Location.Y=322|Color=8388608|FontID=1|IsHidden=T|Text=2|Name=Number of Pins
|RECORD=41|OwnerIndex=413|IndexInSheet=18|OwnerPartId=-1|Location.X=169|Location.Y=322|Color=8388608|FontID=1|IsHidden=T|Text=Lead Free|Name=Lead Free
|RECORD=41|OwnerIndex=413|IndexInSheet=19|OwnerPartId=-1|Location.X=169|Location.Y=322|Color=8388608|FontID=1|IsHidden=T|Text=-|Name=Series
|RECORD=41|OwnerIndex=413|IndexInSheet=20|OwnerPartId=-1|Location.X=169|Location.Y=322|Color=8388608|FontID=1|IsHidden=T|Text=No SVHC|Name=REACH SVHC
|RECORD=41|OwnerIndex=413|IndexInSheet=21|OwnerPartId=-1|Location.X=169|Location.Y=322|Color=8388608|FontID=1|IsHidden=T|Text=1mm|Name=Length
|RECORD=41|OwnerIndex=413|IndexInSheet=22|OwnerPartId=-1|Location.X=169|Location.Y=322|Color=8388608|FontID=1|IsHidden=T|Text=X7R|Name=Dielectric
|RECORD=41|OwnerIndex=413|IndexInSheet=23|OwnerPartId=-1|Location.X=169|Location.Y=322|Color=8388608|FontID=1|IsHidden=T|Text=Yes|Name=RoHS Compliant
|RECORD=41|OwnerIndex=413|IndexInSheet=24|OwnerPartId=-1|Location.X=169|Location.Y=322|Color=8388608|FontID=1|IsHidden=T|Text=Surface Mount|Name=Mount
|RECORD=41|OwnerIndex=413|IndexInSheet=25|OwnerPartId=-1|Location.X=169|Location.Y=322|Color=8388608|FontID=1|IsHidden=T|Text=Tape and Reel|Name=Packaging
|RECORD=41|OwnerIndex=413|IndexInSheet=26|OwnerPartId=-1|Location.X=169|Location.Y=322|Color=8388608|FontID=1|IsHidden=T|Text=0402|Name=Case/Package
|RECORD=41|OwnerIndex=413|IndexInSheet=27|OwnerPartId=-1|Location.X=169|Location.Y=322|Color=8388608|FontID=1|IsHidden=T|Text=0402|Name=Case Code (Imperial)
|RECORD=41|OwnerIndex=413|IndexInSheet=28|OwnerPartId=-1|Location.X=169|Location.Y=322|Color=8388608|FontID=1|IsHidden=T|Text=SMD/SMT|Name=Termination
|RECORD=41|OwnerIndex=413|IndexInSheet=29|OwnerPartId=-1|Location.X=169|Location.Y=322|Color=8388608|FontID=1|IsHidden=T|Text=0.02inch|Name=Width
|RECORD=41|OwnerIndex=413|IndexInSheet=30|OwnerPartId=-1|Location.X=169|Location.Y=322|Color=8388608|FontID=1|IsHidden=T|Text=1005|Name=Case Code (Metric)
|RECORD=41|OwnerIndex=413|IndexInSheet=31|OwnerPartId=-1|Location.X=169|Location.Y=322|Color=8388608|FontID=1|IsHidden=T|Text=10%|Name=Tolerance
|RECORD=34|OwnerIndex=413|IndexInSheet=-1|OwnerPartId=-1|Location.X=170|Location.Y=300|Orientation=1|Color=8388608|FontID=2|Text=C109|Name=Designator|ReadOnlyState=1
|RECORD=41|OwnerIndex=413|IndexInSheet=-1|OwnerPartId=1|Location.X=200|Location.Y=285|Orientation=1|Color=8388608|FontID=2|Text=0.1uF_25V_0402|Name=Comment
|RECORD=44|OwnerIndex=413
|RECORD=45|OwnerIndex=450|IndexInSheet=-1|UseComponentLibrary=T|ModelName=FP-0402-L_1_0_1-W_0_5_0_1-IPC_C|ModelType=PCBLIB|DatafileCount=1|ModelDatafileEntity0=FP-0402-L_1_0_1-W_0_5_0_1-IPC_C|ModelDatafileKind0=PCBLib|IsCurrent=T|DatalinksLocked=T|DatabaseDatalinksLocked=T
|RECORD=46|OwnerIndex=451
|RECORD=48|OwnerIndex=451
|RECORD=45|OwnerIndex=450|IndexInSheet=-1|UseComponentLibrary=T|ModelName=FP-0402-L_1_0_1-W_0_5_0_1-IPC_B|ModelType=PCBLIB|DatafileCount=1|ModelDatafileEntity0=FP-0402-L_1_0_1-W_0_5_0_1-IPC_B|ModelDatafileKind0=PCBLib|DatalinksLocked=T|DatabaseDatalinksLocked=T
|RECORD=46|OwnerIndex=454
|RECORD=48|OwnerIndex=454
|RECORD=45|OwnerIndex=450|IndexInSheet=-1|UseComponentLibrary=T|ModelName=FP-0402-L_1_0_1-W_0_5_0_1-MFG|ModelType=PCBLIB|DatafileCount=1|ModelDatafileEntity0=FP-0402-L_1_0_1-W_0_5_0_1-MFG|ModelDatafileKind0=PCBLib|DatalinksLocked=T|DatabaseDatalinksLocked=T
|RECORD=46|OwnerIndex=457
|RECORD=48|OwnerIndex=457
|RECORD=45|OwnerIndex=450|IndexInSheet=-1|UseComponentLibrary=T|ModelName=FP-0402-L_1_0_1-W_0_5_0_1-IPC_A|ModelType=PCBLIB|DatafileCount=1|ModelDatafileEntity0=FP-0402-L_1_0_1-W_0_5_0_1-IPC_A|ModelDatafileKind0=PCBLib|DatalinksLocked=T|DatabaseDatalinksLocked=T
|RECORD=46|OwnerIndex=460
|RECORD=48|OwnerIndex=460
|RECORD=17|IndexInSheet=52|OwnerPartId=-1|ShowNetName=T|Location.X=180|Location.Y=370|Orientation=1|Color=128|FontID=1|Text=+3.3V
|RECORD=17|IndexInSheet=53|OwnerPartId=-1|Style=4|ShowNetName=T|Location.X=180|Location.Y=290|Orientation=3|Color=128|FontID=1|Text=GND
|RECORD=17|IndexInSheet=54|OwnerPartId=-1|ShowNetName=T|Location.X=150|Location.Y=190|Orientation=2|Color=255|FontID=1|Text=DIP_SW_GPS1_SEL|IsCrossSheetConnector=T
|RECORD=17|IndexInSheet=55|OwnerPartId=-1|Style=4|ShowNetName=T|Location.X=390|Location.Y=130|Orientation=3|Color=128|FontID=1|Text=GND
|RECORD=1|LibReference=RES|PartCount=2|DisplayModeCount=2|IndexInSheet=56|OwnerPartId=-1|Location.X=540|Location.Y=320|CurrentPartId=1|SourceLibraryName=Altium Content Vault|TargetFileName=*|AreaColor=11599871|Color=128|PartIDLocked=F|DesignItemId=CMP-2002-07709-1|AllPinCount=2|ComponentKindVersion2=5
|RECORD=2|OwnerIndex=467|OwnerPartId=1|OwnerPartDisplayMode=1|FormalType=1|Electrical=4|PinConglomerate=32|PinLength=10|Location.X=560|Location.Y=310|Name=2|Designator=2|PinPropagationDelay=0.000000E+000
|RECORD=2|OwnerIndex=467|OwnerPartId=1|OwnerPartDisplayMode=1|FormalType=1|Electrical=4|PinConglomerate=34|PinLength=10|Location.X=540|Location.Y=310|Name=1|Designator=1|PinPropagationDelay=0.000000E+000
|RECORD=14|OwnerIndex=467|IsNotAccesible=T|IndexInSheet=2|OwnerPartId=1|OwnerPartDisplayMode=1|Location.X=540|Location.Y=306|Corner.X=560|Corner.Y=314|LineWidth=1|Color=16711680|AreaColor=11599871
|RECORD=2|OwnerIndex=467|OwnerPartId=1|FormalType=1|Electrical=4|PinConglomerate=32|PinLength=10|Location.X=560|Location.Y=310|Name=2|Designator=2|PinPropagationDelay=0.000000E+000
|RECORD=2|OwnerIndex=467|OwnerPartId=1|FormalType=1|Electrical=4|PinConglomerate=34|PinLength=10|Location.X=540|Location.Y=310|Name=1|Designator=1|PinPropagationDelay=0.000000E+000
|RECORD=6|OwnerIndex=467|IsNotAccesible=T|IndexInSheet=5|OwnerPartId=1|LineWidth=1|Color=16711680|LocationCount=10|X1=560|Y1=310|X2=556|Y2=310|X3=555|Y3=308|X4=553|Y4=312|X5=551|Y5=308|X6=549|Y6=312|X7=547|Y7=308|X8=545|Y8=312|X9=544|Y9=310|X10=540|Y10=310
|RECORD=41|OwnerIndex=467|IndexInSheet=6|OwnerPartId=-1|Location.X=528|Location.Y=323|Color=8388608|FontID=1|IsHidden=T|Text=Yageo / Phycomp|Name=Manufacturer
|RECORD=41|OwnerIndex=467|IndexInSheet=7|OwnerPartId=-1|Location.X=528|Location.Y=323|Color=8388608|FontID=1|IsHidden=T|Text=RC0402FR-0749R9L|Name=Part Number
|RECORD=34|OwnerIndex=467|IndexInSheet=-1|OwnerPartId=-1|Location.X=520|Location.Y=310|Color=8388608|FontID=1|Text=R174|Name=Designator|ReadOnlyState=1
|RECORD=41|OwnerIndex=467|IndexInSheet=-1|OwnerPartId=-1|Location.X=560|Location.Y=310|Color=8388608|FontID=1|Text=DNI_49.9_1%_0402|Name=Comment
|RECORD=44|OwnerIndex=467
|RECORD=45|OwnerIndex=482|IndexInSheet=-1|Description=Chip Resistor, 2-Leads, Body 1.00x0.50mm, IPC High Density|UseComponentLibrary=T|ModelName=RESC1005X40X25LL05T10|ModelType=PCBLIB|DatafileCount=1|ModelDatafileEntity0=RESC1005X40X25LL05T10|ModelDatafileKind0=PCBLib|IsCurrent=T|DatalinksLocked=T|DatabaseDatalinksLocked=T
|RECORD=46|OwnerIndex=483
|RECORD=48|OwnerIndex=483
|RECORD=41|OwnerIndex=485|IndexInSheet=-1|OwnerPartId=-1|Color=8388608|FontID=1|IsHidden=T|Text=2D|Name=Available Preview Images
|RECORD=45|OwnerIndex=482|IndexInSheet=-1|Description=Chip Resistor, 2-Leads, Body 1.00x0.50mm, IPC Low Density|UseComponentLibrary=T|ModelName=RESC1005X40X25ML05T10|ModelType=PCBLIB|DatafileCount=1|ModelDatafileEntity0=RESC1005X40X25ML05T10|ModelDatafileKind0=PCBLib|DatalinksLocked=T|DatabaseDatalinksLocked=T
|RECORD=46|OwnerIndex=487
|RECORD=48|OwnerIndex=487
|RECORD=41|OwnerIndex=489|IndexInSheet=-1|OwnerPartId=-1|Color=8388608|FontID=1|IsHidden=T|Text=2D|Name=Available Preview Images
|RECORD=45|OwnerIndex=482|IndexInSheet=-1|Description=Chip Resistor, 2-Leads, Body 1.00x0.50mm, IPC Medium Density|UseComponentLibrary=T|ModelName=RESC1005X40X25NL05T10|ModelType=PCBLIB|DatafileCount=1|ModelDatafileEntity0=RESC1005X40X25NL05T10|ModelDatafileKind0=PCBLib|DatalinksLocked=T|DatabaseDatalinksLocked=T
|RECORD=46|OwnerIndex=491
|RECORD=48|OwnerIndex=491
|RECORD=41|OwnerIndex=493|IndexInSheet=-1|OwnerPartId=-1|Color=8388608|FontID=1|IsHidden=T|Text=2D|Name=Available Preview Images
|RECORD=1|LibReference=RES|PartCount=2|DisplayModeCount=2|IndexInSheet=57|OwnerPartId=-1|Location.X=540|Location.Y=340|CurrentPartId=1|SourceLibraryName=Altium Content Vault|TargetFileName=*|AreaColor=11599871|Color=128|PartIDLocked=F|DesignItemId=CMP-2002-07709-1|AllPinCount=2|ComponentKindVersion2=5
|RECORD=2|OwnerIndex=495|OwnerPartId=1|OwnerPartDisplayMode=1|FormalType=1|Electrical=4|PinConglomerate=32|PinLength=10|Location.X=560|Location.Y=330|Name=2|Designator=2|PinPropagationDelay=0.000000E+000
|RECORD=2|OwnerIndex=495|OwnerPartId=1|OwnerPartDisplayMode=1|FormalType=1|Electrical=4|PinConglomerate=34|PinLength=10|Location.X=540|Location.Y=330|Name=1|Designator=1|PinPropagationDelay=0.000000E+000
|RECORD=14|OwnerIndex=495|IsNotAccesible=T|IndexInSheet=2|OwnerPartId=1|OwnerPartDisplayMode=1|Location.X=540|Location.Y=326|Corner.X=560|Corner.Y=334|LineWidth=1|Color=16711680|AreaColor=11599871
|RECORD=2|OwnerIndex=495|OwnerPartId=1|FormalType=1|Electrical=4|PinConglomerate=32|PinLength=10|Location.X=560|Location.Y=330|Name=2|Designator=2|PinPropagationDelay=0.000000E+000
|RECORD=2|OwnerIndex=495|OwnerPartId=1|FormalType=1|Electrical=4|PinConglomerate=34|PinLength=10|Location.X=540|Location.Y=330|Name=1|Designator=1|PinPropagationDelay=0.000000E+000
|RECORD=6|OwnerIndex=495|IsNotAccesible=T|IndexInSheet=5|OwnerPartId=1|LineWidth=1|Color=16711680|LocationCount=10|X1=560|Y1=330|X2=556|Y2=330|X3=555|Y3=328|X4=553|Y4=332|X5=551|Y5=328|X6=549|Y6=332|X7=547|Y7=328|X8=545|Y8=332|X9=544|Y9=330|X10=540|Y10=330
|RECORD=41|OwnerIndex=495|IndexInSheet=6|OwnerPartId=-1|Location.X=528|Location.Y=343|Color=8388608|FontID=1|IsHidden=T|Text=Yageo / Phycomp|Name=Manufacturer
|RECORD=41|OwnerIndex=495|IndexInSheet=7|OwnerPartId=-1|Location.X=528|Location.Y=343|Color=8388608|FontID=1|IsHidden=T|Text=RC0402FR-0749R9L|Name=Part Number
|RECORD=34|OwnerIndex=495|IndexInSheet=-1|OwnerPartId=-1|Location.X=520|Location.Y=330|Color=8388608|FontID=1|Text=R172|Name=Designator|ReadOnlyState=1
|RECORD=41|OwnerIndex=495|IndexInSheet=-1|OwnerPartId=-1|Location.X=560|Location.Y=330|Color=8388608|FontID=1|Text=DNI_49.9_1%_0402|Name=Comment
|RECORD=44|OwnerIndex=495
|RECORD=45|OwnerIndex=510|IndexInSheet=-1|Description=Chip Resistor, 2-Leads, Body 1.00x0.50mm, IPC High Density|UseComponentLibrary=T|ModelName=RESC1005X40X25LL05T10|ModelType=PCBLIB|DatafileCount=1|ModelDatafileEntity0=RESC1005X40X25LL05T10|ModelDatafileKind0=PCBLib|IsCurrent=T|DatalinksLocked=T|DatabaseDatalinksLocked=T
|RECORD=46|OwnerIndex=511
|RECORD=48|OwnerIndex=511
|RECORD=41|OwnerIndex=513|IndexInSheet=-1|OwnerPartId=-1|Color=8388608|FontID=1|IsHidden=T|Text=2D|Name=Available Preview Images
|RECORD=45|OwnerIndex=510|IndexInSheet=-1|Description=Chip Resistor, 2-Leads, Body 1.00x0.50mm, IPC Low Density|UseComponentLibrary=T|ModelName=RESC1005X40X25ML05T10|ModelType=PCBLIB|DatafileCount=1|ModelDatafileEntity0=RESC1005X40X25ML05T10|ModelDatafileKind0=PCBLib|DatalinksLocked=T|DatabaseDatalinksLocked=T
|RECORD=46|OwnerIndex=515
|RECORD=48|OwnerIndex=515
|RECORD=41|OwnerIndex=517|IndexInSheet=-1|OwnerPartId=-1|Color=8388608|FontID=1|IsHidden=T|Text=2D|Name=Available Preview Images
|RECORD=45|OwnerIndex=510|IndexInSheet=-1|Description=Chip Resistor, 2-Leads, Body 1.00x0.50mm, IPC Medium Density|UseComponentLibrary=T|ModelName=RESC1005X40X25NL05T10|ModelType=PCBLIB|DatafileCount=1|ModelDatafileEntity0=RESC1005X40X25NL05T10|ModelDatafileKind0=PCBLib|DatalinksLocked=T|DatabaseDatalinksLocked=T
|RECORD=46|OwnerIndex=519
|RECORD=48|OwnerIndex=519
|RECORD=41|OwnerIndex=521|IndexInSheet=-1|OwnerPartId=-1|Color=8388608|FontID=1|IsHidden=T|Text=2D|Name=Available Preview Images
|RECORD=1|LibReference=RES|PartCount=2|DisplayModeCount=2|IndexInSheet=58|OwnerPartId=-1|Location.X=540|Location.Y=350|CurrentPartId=1|SourceLibraryName=Altium Content Vault|TargetFileName=*|AreaColor=11599871|Color=128|PartIDLocked=F|DesignItemId=CMP-2002-07709-1|AllPinCount=2|ComponentKindVersion2=5
|RECORD=2|OwnerIndex=523|OwnerPartId=1|OwnerPartDisplayMode=1|FormalType=1|Electrical=4|PinConglomerate=32|PinLength=10|Location.X=560|Location.Y=340|Name=2|Designator=2|PinPropagationDelay=0.000000E+000
|RECORD=2|OwnerIndex=523|OwnerPartId=1|OwnerPartDisplayMode=1|FormalType=1|Electrical=4|PinConglomerate=34|PinLength=10|Location.X=540|Location.Y=340|Name=1|Designator=1|PinPropagationDelay=0.000000E+000
|RECORD=14|OwnerIndex=523|IsNotAccesible=T|IndexInSheet=2|OwnerPartId=1|OwnerPartDisplayMode=1|Location.X=540|Location.Y=336|Corner.X=560|Corner.Y=344|LineWidth=1|Color=16711680|AreaColor=11599871
|RECORD=2|OwnerIndex=523|OwnerPartId=1|FormalType=1|Electrical=4|PinConglomerate=32|PinLength=10|Location.X=560|Location.Y=340|Name=2|Designator=2|PinPropagationDelay=0.000000E+000
|RECORD=2|OwnerIndex=523|OwnerPartId=1|FormalType=1|Electrical=4|PinConglomerate=34|PinLength=10|Location.X=540|Location.Y=340|Name=1|Designator=1|PinPropagationDelay=0.000000E+000
|RECORD=6|OwnerIndex=523|IsNotAccesible=T|IndexInSheet=5|OwnerPartId=1|LineWidth=1|Color=16711680|LocationCount=10|X1=560|Y1=340|X2=556|Y2=340|X3=555|Y3=338|X4=553|Y4=342|X5=551|Y5=338|X6=549|Y6=342|X7=547|Y7=338|X8=545|Y8=342|X9=544|Y9=340|X10=540|Y10=340
|RECORD=41|OwnerIndex=523|IndexInSheet=6|OwnerPartId=-1|Location.X=528|Location.Y=353|Color=8388608|FontID=1|IsHidden=T|Text=Yageo / Phycomp|Name=Manufacturer
|RECORD=41|OwnerIndex=523|IndexInSheet=7|OwnerPartId=-1|Location.X=528|Location.Y=353|Color=8388608|FontID=1|IsHidden=T|Text=RC0402FR-0749R9L|Name=Part Number
|RECORD=34|OwnerIndex=523|IndexInSheet=-1|OwnerPartId=-1|Location.X=520|Location.Y=340|Color=8388608|FontID=1|Text=R170|Name=Designator|ReadOnlyState=1
|RECORD=41|OwnerIndex=523|IndexInSheet=-1|OwnerPartId=-1|Location.X=560|Location.Y=340|Color=8388608|FontID=1|Text=DNI_49.9_1%_0402|Name=Comment
|RECORD=44|OwnerIndex=523
|RECORD=45|OwnerIndex=538|IndexInSheet=-1|Description=Chip Resistor, 2-Leads, Body 1.00x0.50mm, IPC High Density|UseComponentLibrary=T|ModelName=RESC1005X40X25LL05T10|ModelType=PCBLIB|DatafileCount=1|ModelDatafileEntity0=RESC1005X40X25LL05T10|ModelDatafileKind0=PCBLib|IsCurrent=T|DatalinksLocked=T|DatabaseDatalinksLocked=T
|RECORD=46|OwnerIndex=539
|RECORD=48|OwnerIndex=539
|RECORD=41|OwnerIndex=541|IndexInSheet=-1|OwnerPartId=-1|Color=8388608|FontID=1|IsHidden=T|Text=2D|Name=Available Preview Images
|RECORD=45|OwnerIndex=538|IndexInSheet=-1|Description=Chip Resistor, 2-Leads, Body 1.00x0.50mm, IPC Low Density|UseComponentLibrary=T|ModelName=RESC1005X40X25ML05T10|ModelType=PCBLIB|DatafileCount=1|ModelDatafileEntity0=RESC1005X40X25ML05T10|ModelDatafileKind0=PCBLib|DatalinksLocked=T|DatabaseDatalinksLocked=T
|RECORD=46|OwnerIndex=543
|RECORD=48|OwnerIndex=543
|RECORD=41|OwnerIndex=545|IndexInSheet=-1|OwnerPartId=-1|Color=8388608|FontID=1|IsHidden=T|Text=2D|Name=Available Preview Images
|RECORD=45|OwnerIndex=538|IndexInSheet=-1|Description=Chip Resistor, 2-Leads, Body 1.00x0.50mm, IPC Medium Density|UseComponentLibrary=T|ModelName=RESC1005X40X25NL05T10|ModelType=PCBLIB|DatafileCount=1|ModelDatafileEntity0=RESC1005X40X25NL05T10|ModelDatafileKind0=PCBLib|DatalinksLocked=T|DatabaseDatalinksLocked=T
|RECORD=46|OwnerIndex=547
|RECORD=48|OwnerIndex=547
|RECORD=41|OwnerIndex=549|IndexInSheet=-1|OwnerPartId=-1|Color=8388608|FontID=1|IsHidden=T|Text=2D|Name=Available Preview Images
|RECORD=1|LibReference=RES|PartCount=2|DisplayModeCount=2|IndexInSheet=59|OwnerPartId=-1|Location.X=540|Location.Y=330|CurrentPartId=1|SourceLibraryName=Altium Content Vault|TargetFileName=*|AreaColor=11599871|Color=128|PartIDLocked=F|DesignItemId=CMP-2002-07709-1|AllPinCount=2|ComponentKindVersion2=5
|RECORD=2|OwnerIndex=551|OwnerPartId=1|OwnerPartDisplayMode=1|FormalType=1|Electrical=4|PinConglomerate=32|PinLength=10|Location.X=560|Location.Y=320|Name=2|Designator=2|PinPropagationDelay=0.000000E+000
|RECORD=2|OwnerIndex=551|OwnerPartId=1|OwnerPartDisplayMode=1|FormalType=1|Electrical=4|PinConglomerate=34|PinLength=10|Location.X=540|Location.Y=320|Name=1|Designator=1|PinPropagationDelay=0.000000E+000
|RECORD=14|OwnerIndex=551|IsNotAccesible=T|IndexInSheet=2|OwnerPartId=1|OwnerPartDisplayMode=1|Location.X=540|Location.Y=316|Corner.X=560|Corner.Y=324|LineWidth=1|Color=16711680|AreaColor=11599871
|RECORD=2|OwnerIndex=551|OwnerPartId=1|FormalType=1|Electrical=4|PinConglomerate=32|PinLength=10|Location.X=560|Location.Y=320|Name=2|Designator=2|PinPropagationDelay=0.000000E+000
|RECORD=2|OwnerIndex=551|OwnerPartId=1|FormalType=1|Electrical=4|PinConglomerate=34|PinLength=10|Location.X=540|Location.Y=320|Name=1|Designator=1|PinPropagationDelay=0.000000E+000
|RECORD=6|OwnerIndex=551|IsNotAccesible=T|IndexInSheet=5|OwnerPartId=1|LineWidth=1|Color=16711680|LocationCount=10|X1=560|Y1=320|X2=556|Y2=320|X3=555|Y3=318|X4=553|Y4=322|X5=551|Y5=318|X6=549|Y6=322|X7=547|Y7=318|X8=545|Y8=322|X9=544|Y9=320|X10=540|Y10=320
|RECORD=41|OwnerIndex=551|IndexInSheet=6|OwnerPartId=-1|Location.X=528|Location.Y=333|Color=8388608|FontID=1|IsHidden=T|Text=Yageo / Phycomp|Name=Manufacturer
|RECORD=41|OwnerIndex=551|IndexInSheet=7|OwnerPartId=-1|Location.X=528|Location.Y=333|Color=8388608|FontID=1|IsHidden=T|Text=RC0402FR-0749R9L|Name=Part Number
|RECORD=34|OwnerIndex=551|IndexInSheet=-1|OwnerPartId=-1|Location.X=520|Location.Y=320|Color=8388608|FontID=1|Text=R173|Name=Designator|ReadOnlyState=1
|RECORD=41|OwnerIndex=551|IndexInSheet=-1|OwnerPartId=-1|Location.X=560|Location.Y=320|Color=8388608|FontID=1|Text=DNI_49.9_1%_0402|Name=Comment
|RECORD=44|OwnerIndex=551
|RECORD=45|OwnerIndex=566|IndexInSheet=-1|Description=Chip Resistor, 2-Leads, Body 1.00x0.50mm, IPC High Density|UseComponentLibrary=T|ModelName=RESC1005X40X25LL05T10|ModelType=PCBLIB|DatafileCount=1|ModelDatafileEntity0=RESC1005X40X25LL05T10|ModelDatafileKind0=PCBLib|IsCurrent=T|DatalinksLocked=T|DatabaseDatalinksLocked=T
|RECORD=46|OwnerIndex=567
|RECORD=48|OwnerIndex=567
|RECORD=41|OwnerIndex=569|IndexInSheet=-1|OwnerPartId=-1|Color=8388608|FontID=1|IsHidden=T|Text=2D|Name=Available Preview Images
|RECORD=45|OwnerIndex=566|IndexInSheet=-1|Description=Chip Resistor, 2-Leads, Body 1.00x0.50mm, IPC Low Density|UseComponentLibrary=T|ModelName=RESC1005X40X25ML05T10|ModelType=PCBLIB|DatafileCount=1|ModelDatafileEntity0=RESC1005X40X25ML05T10|ModelDatafileKind0=PCBLib|DatalinksLocked=T|DatabaseDatalinksLocked=T
|RECORD=46|OwnerIndex=571
|RECORD=48|OwnerIndex=571
|RECORD=41|OwnerIndex=573|IndexInSheet=-1|OwnerPartId=-1|Color=8388608|FontID=1|IsHidden=T|Text=2D|Name=Available Preview Images
|RECORD=45|OwnerIndex=566|IndexInSheet=-1|Description=Chip Resistor, 2-Leads, Body 1.00x0.50mm, IPC Medium Density|UseComponentLibrary=T|ModelName=RESC1005X40X25NL05T10|ModelType=PCBLIB|DatafileCount=1|ModelDatafileEntity0=RESC1005X40X25NL05T10|ModelDatafileKind0=PCBLib|DatalinksLocked=T|DatabaseDatalinksLocked=T
|RECORD=46|OwnerIndex=575
|RECORD=48|OwnerIndex=575
|RECORD=41|OwnerIndex=577|IndexInSheet=-1|OwnerPartId=-1|Color=8388608|FontID=1|IsHidden=T|Text=2D|Name=Available Preview Images
|RECORD=1|LibReference=RES|PartCount=2|DisplayModeCount=2|IndexInSheet=60|OwnerPartId=-1|Location.X=410|Location.Y=280|CurrentPartId=1|SourceLibraryName=Altium Content Vault|TargetFileName=*|AreaColor=11599871|Color=128|PartIDLocked=F|DesignItemId=CMP-2002-07709-1|AllPinCount=2
|RECORD=2|OwnerIndex=579|OwnerPartId=1|OwnerPartDisplayMode=1|FormalType=1|Electrical=4|PinConglomerate=32|PinLength=10|Location.X=430|Location.Y=270|Name=2|Designator=2|PinPropagationDelay=0.000000E+000
|RECORD=2|OwnerIndex=579|OwnerPartId=1|OwnerPartDisplayMode=1|FormalType=1|Electrical=4|PinConglomerate=34|PinLength=10|Location.X=410|Location.Y=270|Name=1|Designator=1|PinPropagationDelay=0.000000E+000
|RECORD=14|OwnerIndex=579|IsNotAccesible=T|IndexInSheet=2|OwnerPartId=1|OwnerPartDisplayMode=1|Location.X=410|Location.Y=266|Corner.X=430|Corner.Y=274|LineWidth=1|Color=16711680|AreaColor=11599871
|RECORD=2|OwnerIndex=579|OwnerPartId=1|FormalType=1|Electrical=4|PinConglomerate=32|PinLength=10|Location.X=430|Location.Y=270|Name=2|Designator=2|PinPropagationDelay=0.000000E+000
|RECORD=2|OwnerIndex=579|OwnerPartId=1|FormalType=1|Electrical=4|PinConglomerate=34|PinLength=10|Location.X=410|Location.Y=270|Name=1|Designator=1|PinPropagationDelay=0.000000E+000
|RECORD=6|OwnerIndex=579|IsNotAccesible=T|IndexInSheet=5|OwnerPartId=1|LineWidth=1|Color=16711680|LocationCount=10|X1=430|Y1=270|X2=426|Y2=270|X3=425|Y3=268|X4=423|Y4=272|X5=421|Y5=268|X6=419|Y6=272|X7=417|Y7=268|X8=415|Y8=272|X9=414|Y9=270|X10=410|Y10=270
|RECORD=41|OwnerIndex=579|IndexInSheet=6|OwnerPartId=-1|Location.X=398|Location.Y=283|Color=8388608|FontID=1|IsHidden=T|Text=Yageo / Phycomp|Name=Manufacturer
|RECORD=41|OwnerIndex=579|IndexInSheet=7|OwnerPartId=-1|Location.X=398|Location.Y=283|Color=8388608|FontID=1|IsHidden=T|Text=RC0402FR-0749R9L|Name=Part Number
|RECORD=34|OwnerIndex=579|IndexInSheet=-1|OwnerPartId=-1|Location.X=390|Location.Y=270|Color=8388608|FontID=1|Text=R176|Name=Designator|ReadOnlyState=1
|RECORD=41|OwnerIndex=579|IndexInSheet=-1|OwnerPartId=-1|Location.X=430|Location.Y=270|Color=8388608|FontID=1|Text=49.9_1%_0402|Name=Comment
|RECORD=44|OwnerIndex=579
|RECORD=45|OwnerIndex=594|IndexInSheet=-1|Description=Chip Resistor, 2-Leads, Body 1.00x0.50mm, IPC High Density|UseComponentLibrary=T|ModelName=RESC1005X40X25LL05T10|ModelType=PCBLIB|DatafileCount=1|ModelDatafileEntity0=RESC1005X40X25LL05T10|ModelDatafileKind0=PCBLib|IsCurrent=T|DatalinksLocked=T|DatabaseDatalinksLocked=T
|RECORD=46|OwnerIndex=595
|RECORD=48|OwnerIndex=595
|RECORD=41|OwnerIndex=597|IndexInSheet=-1|OwnerPartId=-1|Color=8388608|FontID=1|IsHidden=T|Text=2D|Name=Available Preview Images
|RECORD=45|OwnerIndex=594|IndexInSheet=-1|Description=Chip Resistor, 2-Leads, Body 1.00x0.50mm, IPC Low Density|UseComponentLibrary=T|ModelName=RESC1005X40X25ML05T10|ModelType=PCBLIB|DatafileCount=1|ModelDatafileEntity0=RESC1005X40X25ML05T10|ModelDatafileKind0=PCBLib|DatalinksLocked=T|DatabaseDatalinksLocked=T
|RECORD=46|OwnerIndex=599
|RECORD=48|OwnerIndex=599
|RECORD=41|OwnerIndex=601|IndexInSheet=-1|OwnerPartId=-1|Color=8388608|FontID=1|IsHidden=T|Text=2D|Name=Available Preview Images
|RECORD=45|OwnerIndex=594|IndexInSheet=-1|Description=Chip Resistor, 2-Leads, Body 1.00x0.50mm, IPC Medium Density|UseComponentLibrary=T|ModelName=RESC1005X40X25NL05T10|ModelType=PCBLIB|DatafileCount=1|ModelDatafileEntity0=RESC1005X40X25NL05T10|ModelDatafileKind0=PCBLib|DatalinksLocked=T|DatabaseDatalinksLocked=T
|RECORD=46|OwnerIndex=603
|RECORD=48|OwnerIndex=603
|RECORD=41|OwnerIndex=605|IndexInSheet=-1|OwnerPartId=-1|Color=8388608|FontID=1|IsHidden=T|Text=2D|Name=Available Preview Images
|RECORD=1|LibReference=RES|PartCount=2|DisplayModeCount=2|IndexInSheet=61|OwnerPartId=-1|Location.X=410|Location.Y=240|CurrentPartId=1|SourceLibraryName=Altium Content Vault|TargetFileName=*|AreaColor=11599871|Color=128|PartIDLocked=F|DesignItemId=CMP-2002-07709-1|AllPinCount=2
|RECORD=2|OwnerIndex=607|OwnerPartId=1|OwnerPartDisplayMode=1|FormalType=1|Electrical=4|PinConglomerate=32|PinLength=10|Location.X=430|Location.Y=230|Name=2|Designator=2|PinPropagationDelay=0.000000E+000
|RECORD=2|OwnerIndex=607|OwnerPartId=1|OwnerPartDisplayMode=1|FormalType=1|Electrical=4|PinConglomerate=34|PinLength=10|Location.X=410|Location.Y=230|Name=1|Designator=1|PinPropagationDelay=0.000000E+000
|RECORD=14|OwnerIndex=607|IsNotAccesible=T|IndexInSheet=2|OwnerPartId=1|OwnerPartDisplayMode=1|Location.X=410|Location.Y=226|Corner.X=430|Corner.Y=234|LineWidth=1|Color=16711680|AreaColor=11599871
|RECORD=2|OwnerIndex=607|OwnerPartId=1|FormalType=1|Electrical=4|PinConglomerate=32|PinLength=10|Location.X=430|Location.Y=230|Name=2|Designator=2|PinPropagationDelay=0.000000E+000
|RECORD=2|OwnerIndex=607|OwnerPartId=1|FormalType=1|Electrical=4|PinConglomerate=34|PinLength=10|Location.X=410|Location.Y=230|Name=1|Designator=1|PinPropagationDelay=0.000000E+000
|RECORD=6|OwnerIndex=607|IsNotAccesible=T|IndexInSheet=5|OwnerPartId=1|LineWidth=1|Color=16711680|LocationCount=10|X1=430|Y1=230|X2=426|Y2=230|X3=425|Y3=228|X4=423|Y4=232|X5=421|Y5=228|X6=419|Y6=232|X7=417|Y7=228|X8=415|Y8=232|X9=414|Y9=230|X10=410|Y10=230
|RECORD=41|OwnerIndex=607|IndexInSheet=6|OwnerPartId=-1|Location.X=398|Location.Y=243|Color=8388608|FontID=1|IsHidden=T|Text=Yageo / Phycomp|Name=Manufacturer
|RECORD=41|OwnerIndex=607|IndexInSheet=7|OwnerPartId=-1|Location.X=398|Location.Y=243|Color=8388608|FontID=1|IsHidden=T|Text=RC0402FR-0749R9L|Name=Part Number
|RECORD=34|OwnerIndex=607|IndexInSheet=-1|OwnerPartId=-1|Location.X=390|Location.Y=230|Color=8388608|FontID=1|Text=R177|Name=Designator|ReadOnlyState=1
|RECORD=41|OwnerIndex=607|IndexInSheet=-1|OwnerPartId=-1|Location.X=430|Location.Y=230|Color=8388608|FontID=1|Text=49.9_1%_0402|Name=Comment
|RECORD=44|OwnerIndex=607
|RECORD=45|OwnerIndex=622|IndexInSheet=-1|Description=Chip Resistor, 2-Leads, Body 1.00x0.50mm, IPC High Density|UseComponentLibrary=T|ModelName=RESC1005X40X25LL05T10|ModelType=PCBLIB|DatafileCount=1|ModelDatafileEntity0=RESC1005X40X25LL05T10|ModelDatafileKind0=PCBLib|IsCurrent=T|DatalinksLocked=T|DatabaseDatalinksLocked=T
|RECORD=46|OwnerIndex=623
|RECORD=48|OwnerIndex=623
|RECORD=41|OwnerIndex=625|IndexInSheet=-1|OwnerPartId=-1|Color=8388608|FontID=1|IsHidden=T|Text=2D|Name=Available Preview Images
|RECORD=45|OwnerIndex=622|IndexInSheet=-1|Description=Chip Resistor, 2-Leads, Body 1.00x0.50mm, IPC Low Density|UseComponentLibrary=T|ModelName=RESC1005X40X25ML05T10|ModelType=PCBLIB|DatafileCount=1|ModelDatafileEntity0=RESC1005X40X25ML05T10|ModelDatafileKind0=PCBLib|DatalinksLocked=T|DatabaseDatalinksLocked=T
|RECORD=46|OwnerIndex=627
|RECORD=48|OwnerIndex=627
|RECORD=41|OwnerIndex=629|IndexInSheet=-1|OwnerPartId=-1|Color=8388608|FontID=1|IsHidden=T|Text=2D|Name=Available Preview Images
|RECORD=45|OwnerIndex=622|IndexInSheet=-1|Description=Chip Resistor, 2-Leads, Body 1.00x0.50mm, IPC Medium Density|UseComponentLibrary=T|ModelName=RESC1005X40X25NL05T10|ModelType=PCBLIB|DatafileCount=1|ModelDatafileEntity0=RESC1005X40X25NL05T10|ModelDatafileKind0=PCBLib|DatalinksLocked=T|DatabaseDatalinksLocked=T
|RECORD=46|OwnerIndex=631
|RECORD=48|OwnerIndex=631
|RECORD=41|OwnerIndex=633|IndexInSheet=-1|OwnerPartId=-1|Color=8388608|FontID=1|IsHidden=T|Text=2D|Name=Available Preview Images
|RECORD=1|LibReference=RES|PartCount=2|DisplayModeCount=2|IndexInSheet=62|OwnerPartId=-1|Location.X=470|Location.Y=450|CurrentPartId=1|SourceLibraryName=Altium Content Vault|TargetFileName=*|AreaColor=11599871|Color=128|PartIDLocked=F|DesignItemId=CMP-2002-08434-1|AllPinCount=2|ComponentKindVersion2=5
|RECORD=2|OwnerIndex=635|OwnerPartId=1|OwnerPartDisplayMode=1|FormalType=1|Electrical=4|PinConglomerate=32|PinLength=10|Location.X=490|Location.Y=440|Name=2|Designator=2|PinPropagationDelay=0.000000E+000
|RECORD=2|OwnerIndex=635|OwnerPartId=1|OwnerPartDisplayMode=1|FormalType=1|Electrical=4|PinConglomerate=34|PinLength=10|Location.X=470|Location.Y=440|Name=1|Designator=1|PinPropagationDelay=0.000000E+000
|RECORD=14|OwnerIndex=635|IsNotAccesible=T|IndexInSheet=2|OwnerPartId=1|OwnerPartDisplayMode=1|Location.X=470|Location.Y=436|Corner.X=490|Corner.Y=444|LineWidth=1|Color=16711680|AreaColor=11599871
|RECORD=2|OwnerIndex=635|OwnerPartId=1|FormalType=1|Electrical=4|PinConglomerate=32|PinLength=10|Location.X=490|Location.Y=440|Name=2|Designator=2|PinPropagationDelay=0.000000E+000
|RECORD=2|OwnerIndex=635|OwnerPartId=1|FormalType=1|Electrical=4|PinConglomerate=34|PinLength=10|Location.X=470|Location.Y=440|Name=1|Designator=1|PinPropagationDelay=0.000000E+000
|RECORD=6|OwnerIndex=635|IsNotAccesible=T|IndexInSheet=5|OwnerPartId=1|LineWidth=1|Color=16711680|LocationCount=10|X1=490|Y1=440|X2=486|Y2=440|X3=485|Y3=438|X4=483|Y4=442|X5=481|Y5=438|X6=479|Y6=442|X7=477|Y7=438|X8=475|Y8=442|X9=474|Y9=440|X10=470|Y10=440
|RECORD=41|OwnerIndex=635|IndexInSheet=6|OwnerPartId=-1|Location.X=458|Location.Y=453|Color=8388608|FontID=1|IsHidden=T|Text=CRCW040227R0FKED|Name=Part Number
|RECORD=41|OwnerIndex=635|IndexInSheet=7|OwnerPartId=-1|Location.X=458|Location.Y=453|Color=8388608|FontID=1|IsHidden=T|Text=Vishay Dale|Name=Manufacturer
|RECORD=34|OwnerIndex=635|IndexInSheet=-1|OwnerPartId=-1|Location.X=450|Location.Y=440|Color=8388608|FontID=1|Text=R162|Name=Designator|ReadOnlyState=1
|RECORD=41|OwnerIndex=635|IndexInSheet=-1|OwnerPartId=-1|Location.X=470|Location.Y=440|Color=8388608|FontID=1|Text=DNI_27_1%_0402|Name=Comment
|RECORD=44|OwnerIndex=635
|RECORD=45|OwnerIndex=650|IndexInSheet=-1|Description=Chip Resistor, 2-Leads, Body 1.00x0.50mm, IPC Medium Density|UseComponentLibrary=T|ModelName=RESC1005X40X25NL05T05|ModelType=PCBLIB|DatafileCount=1|ModelDatafileEntity0=RESC1005X40X25NL05T05|ModelDatafileKind0=PCBLib|IsCurrent=T|DatalinksLocked=T|DatabaseDatalinksLocked=T
|RECORD=46|OwnerIndex=651
|RECORD=48|OwnerIndex=651
|RECORD=41|OwnerIndex=653|IndexInSheet=-1|OwnerPartId=-1|Color=8388608|FontID=1|IsHidden=T|Text=2D|Name=Available Preview Images
|RECORD=45|OwnerIndex=650|IndexInSheet=-1|Description=Chip Resistor, 2-Leads, Body 1.00x0.50mm, IPC High Density|UseComponentLibrary=T|ModelName=RESC1005X40X25LL05T05|ModelType=PCBLIB|DatafileCount=1|ModelDatafileEntity0=RESC1005X40X25LL05T05|ModelDatafileKind0=PCBLib|DatalinksLocked=T|DatabaseDatalinksLocked=T
|RECORD=46|OwnerIndex=655
|RECORD=48|OwnerIndex=655
|RECORD=41|OwnerIndex=657|IndexInSheet=-1|OwnerPartId=-1|Color=8388608|FontID=1|IsHidden=T|Text=2D|Name=Available Preview Images
|RECORD=45|OwnerIndex=650|IndexInSheet=-1|Description=Chip Resistor, 2-Leads, Body 1.00x0.50mm, IPC Low Density|UseComponentLibrary=T|ModelName=RESC1005X40X25ML05T05|ModelType=PCBLIB|DatafileCount=1|ModelDatafileEntity0=RESC1005X40X25ML05T05|ModelDatafileKind0=PCBLib|DatalinksLocked=T|DatabaseDatalinksLocked=T
|RECORD=46|OwnerIndex=659
|RECORD=48|OwnerIndex=659
|RECORD=41|OwnerIndex=661|IndexInSheet=-1|OwnerPartId=-1|Color=8388608|FontID=1|IsHidden=T|Text=2D|Name=Available Preview Images
|RECORD=1|LibReference=RES|PartCount=2|DisplayModeCount=2|IndexInSheet=63|OwnerPartId=-1|Location.X=470|Location.Y=440|CurrentPartId=1|SourceLibraryName=Altium Content Vault|TargetFileName=*|AreaColor=11599871|Color=128|PartIDLocked=F|DesignItemId=CMP-2002-08434-1|AllPinCount=2|ComponentKindVersion2=5
|RECORD=2|OwnerIndex=663|OwnerPartId=1|OwnerPartDisplayMode=1|FormalType=1|Electrical=4|PinConglomerate=32|PinLength=10|Location.X=490|Location.Y=430|Name=2|Designator=2|PinPropagationDelay=0.000000E+000
|RECORD=2|OwnerIndex=663|OwnerPartId=1|OwnerPartDisplayMode=1|FormalType=1|Electrical=4|PinConglomerate=34|PinLength=10|Location.X=470|Location.Y=430|Name=1|Designator=1|PinPropagationDelay=0.000000E+000
|RECORD=14|OwnerIndex=663|IsNotAccesible=T|IndexInSheet=2|OwnerPartId=1|OwnerPartDisplayMode=1|Location.X=470|Location.Y=426|Corner.X=490|Corner.Y=434|LineWidth=1|Color=16711680|AreaColor=11599871
|RECORD=2|OwnerIndex=663|OwnerPartId=1|FormalType=1|Electrical=4|PinConglomerate=32|PinLength=10|Location.X=490|Location.Y=430|Name=2|Designator=2|PinPropagationDelay=0.000000E+000
|RECORD=2|OwnerIndex=663|OwnerPartId=1|FormalType=1|Electrical=4|PinConglomerate=34|PinLength=10|Location.X=470|Location.Y=430|Name=1|Designator=1|PinPropagationDelay=0.000000E+000
|RECORD=6|OwnerIndex=663|IsNotAccesible=T|IndexInSheet=5|OwnerPartId=1|LineWidth=1|Color=16711680|LocationCount=10|X1=490|Y1=430|X2=486|Y2=430|X3=485|Y3=428|X4=483|Y4=432|X5=481|Y5=428|X6=479|Y6=432|X7=477|Y7=428|X8=475|Y8=432|X9=474|Y9=430|X10=470|Y10=430
|RECORD=41|OwnerIndex=663|IndexInSheet=6|OwnerPartId=-1|Location.X=458|Location.Y=443|Color=8388608|FontID=1|IsHidden=T|Text=CRCW040227R0FKED|Name=Part Number
|RECORD=41|OwnerIndex=663|IndexInSheet=7|OwnerPartId=-1|Location.X=458|Location.Y=443|Color=8388608|FontID=1|IsHidden=T|Text=Vishay Dale|Name=Manufacturer
|RECORD=34|OwnerIndex=663|IndexInSheet=-1|OwnerPartId=-1|Location.X=450|Location.Y=430|Color=8388608|FontID=1|Text=R163|Name=Designator|ReadOnlyState=1
|RECORD=41|OwnerIndex=663|IndexInSheet=-1|OwnerPartId=-1|Location.X=470|Location.Y=430|Color=8388608|FontID=1|Text=DNI_27_1%_0402|Name=Comment
|RECORD=44|OwnerIndex=663
|RECORD=45|OwnerIndex=678|IndexInSheet=-1|Description=Chip Resistor, 2-Leads, Body 1.00x0.50mm, IPC Medium Density|UseComponentLibrary=T|ModelName=RESC1005X40X25NL05T05|ModelType=PCBLIB|DatafileCount=1|ModelDatafileEntity0=RESC1005X40X25NL05T05|ModelDatafileKind0=PCBLib|IsCurrent=T|DatalinksLocked=T|DatabaseDatalinksLocked=T
|RECORD=46|OwnerIndex=679
|RECORD=48|OwnerIndex=679
|RECORD=41|OwnerIndex=681|IndexInSheet=-1|OwnerPartId=-1|Color=8388608|FontID=1|IsHidden=T|Text=2D|Name=Available Preview Images
|RECORD=45|OwnerIndex=678|IndexInSheet=-1|Description=Chip Resistor, 2-Leads, Body 1.00x0.50mm, IPC High Density|UseComponentLibrary=T|ModelName=RESC1005X40X25LL05T05|ModelType=PCBLIB|DatafileCount=1|ModelDatafileEntity0=RESC1005X40X25LL05T05|ModelDatafileKind0=PCBLib|DatalinksLocked=T|DatabaseDatalinksLocked=T
|RECORD=46|OwnerIndex=683
|RECORD=48|OwnerIndex=683
|RECORD=41|OwnerIndex=685|IndexInSheet=-1|OwnerPartId=-1|Color=8388608|FontID=1|IsHidden=T|Text=2D|Name=Available Preview Images
|RECORD=45|OwnerIndex=678|IndexInSheet=-1|Description=Chip Resistor, 2-Leads, Body 1.00x0.50mm, IPC Low Density|UseComponentLibrary=T|ModelName=RESC1005X40X25ML05T05|ModelType=PCBLIB|DatafileCount=1|ModelDatafileEntity0=RESC1005X40X25ML05T05|ModelDatafileKind0=PCBLib|DatalinksLocked=T|DatabaseDatalinksLocked=T
|RECORD=46|OwnerIndex=687
|RECORD=48|OwnerIndex=687
|RECORD=41|OwnerIndex=689|IndexInSheet=-1|OwnerPartId=-1|Color=8388608|FontID=1|IsHidden=T|Text=2D|Name=Available Preview Images
|RECORD=1|LibReference=RES|PartCount=2|DisplayModeCount=2|IndexInSheet=64|OwnerPartId=-1|Location.X=470|Location.Y=420|CurrentPartId=1|SourceLibraryName=Altium Content Vault|TargetFileName=*|AreaColor=11599871|Color=128|PartIDLocked=F|DesignItemId=CMP-2002-08434-1|AllPinCount=2|ComponentKindVersion2=5
|RECORD=2|OwnerIndex=691|OwnerPartId=1|OwnerPartDisplayMode=1|FormalType=1|Electrical=4|PinConglomerate=32|PinLength=10|Location.X=490|Location.Y=410|Name=2|Designator=2|PinPropagationDelay=0.000000E+000
|RECORD=2|OwnerIndex=691|OwnerPartId=1|OwnerPartDisplayMode=1|FormalType=1|Electrical=4|PinConglomerate=34|PinLength=10|Location.X=470|Location.Y=410|Name=1|Designator=1|PinPropagationDelay=0.000000E+000
|RECORD=14|OwnerIndex=691|IsNotAccesible=T|IndexInSheet=2|OwnerPartId=1|OwnerPartDisplayMode=1|Location.X=470|Location.Y=406|Corner.X=490|Corner.Y=414|LineWidth=1|Color=16711680|AreaColor=11599871
|RECORD=2|OwnerIndex=691|OwnerPartId=1|FormalType=1|Electrical=4|PinConglomerate=32|PinLength=10|Location.X=490|Location.Y=410|Name=2|Designator=2|PinPropagationDelay=0.000000E+000
|RECORD=2|OwnerIndex=691|OwnerPartId=1|FormalType=1|Electrical=4|PinConglomerate=34|PinLength=10|Location.X=470|Location.Y=410|Name=1|Designator=1|PinPropagationDelay=0.000000E+000
|RECORD=6|OwnerIndex=691|IsNotAccesible=T|IndexInSheet=5|OwnerPartId=1|LineWidth=1|Color=16711680|LocationCount=10|X1=490|Y1=410|X2=486|Y2=410|X3=485|Y3=408|X4=483|Y4=412|X5=481|Y5=408|X6=479|Y6=412|X7=477|Y7=408|X8=475|Y8=412|X9=474|Y9=410|X10=470|Y10=410
|RECORD=41|OwnerIndex=691|IndexInSheet=6|OwnerPartId=-1|Location.X=458|Location.Y=423|Color=8388608|FontID=1|IsHidden=T|Text=CRCW040227R0FKED|Name=Part Number
|RECORD=41|OwnerIndex=691|IndexInSheet=7|OwnerPartId=-1|Location.X=458|Location.Y=423|Color=8388608|FontID=1|IsHidden=T|Text=Vishay Dale|Name=Manufacturer
|RECORD=34|OwnerIndex=691|IndexInSheet=-1|OwnerPartId=-1|Location.X=450|Location.Y=410|Color=8388608|FontID=1|Text=R165|Name=Designator|ReadOnlyState=1
|RECORD=41|OwnerIndex=691|IndexInSheet=-1|OwnerPartId=-1|Location.X=470|Location.Y=410|Color=8388608|FontID=1|Text=DNI_27_1%_0402|Name=Comment
|RECORD=44|OwnerIndex=691
|RECORD=45|OwnerIndex=706|IndexInSheet=-1|Description=Chip Resistor, 2-Leads, Body 1.00x0.50mm, IPC Medium Density|UseComponentLibrary=T|ModelName=RESC1005X40X25NL05T05|ModelType=PCBLIB|DatafileCount=1|ModelDatafileEntity0=RESC1005X40X25NL05T05|ModelDatafileKind0=PCBLib|IsCurrent=T|DatalinksLocked=T|DatabaseDatalinksLocked=T
|RECORD=46|OwnerIndex=707
|RECORD=48|OwnerIndex=707
|RECORD=41|OwnerIndex=709|IndexInSheet=-1|OwnerPartId=-1|Color=8388608|FontID=1|IsHidden=T|Text=2D|Name=Available Preview Images
|RECORD=45|OwnerIndex=706|IndexInSheet=-1|Description=Chip Resistor, 2-Leads, Body 1.00x0.50mm, IPC High Density|UseComponentLibrary=T|ModelName=RESC1005X40X25LL05T05|ModelType=PCBLIB|DatafileCount=1|ModelDatafileEntity0=RESC1005X40X25LL05T05|ModelDatafileKind0=PCBLib|DatalinksLocked=T|DatabaseDatalinksLocked=T
|RECORD=46|OwnerIndex=711
|RECORD=48|OwnerIndex=711
|RECORD=41|OwnerIndex=713|IndexInSheet=-1|OwnerPartId=-1|Color=8388608|FontID=1|IsHidden=T|Text=2D|Name=Available Preview Images
|RECORD=45|OwnerIndex=706|IndexInSheet=-1|Description=Chip Resistor, 2-Leads, Body 1.00x0.50mm, IPC Low Density|UseComponentLibrary=T|ModelName=RESC1005X40X25ML05T05|ModelType=PCBLIB|DatafileCount=1|ModelDatafileEntity0=RESC1005X40X25ML05T05|ModelDatafileKind0=PCBLib|DatalinksLocked=T|DatabaseDatalinksLocked=T
|RECORD=46|OwnerIndex=715
|RECORD=48|OwnerIndex=715
|RECORD=41|OwnerIndex=717|IndexInSheet=-1|OwnerPartId=-1|Color=8388608|FontID=1|IsHidden=T|Text=2D|Name=Available Preview Images
|RECORD=1|LibReference=RES|PartCount=2|DisplayModeCount=2|IndexInSheet=65|OwnerPartId=-1|Location.X=470|Location.Y=430|CurrentPartId=1|SourceLibraryName=Altium Content Vault|TargetFileName=*|AreaColor=11599871|Color=128|PartIDLocked=F|DesignItemId=CMP-2002-08434-1|AllPinCount=2|ComponentKindVersion2=5
|RECORD=2|OwnerIndex=719|OwnerPartId=1|OwnerPartDisplayMode=1|FormalType=1|Electrical=4|PinConglomerate=32|PinLength=10|Location.X=490|Location.Y=420|Name=2|Designator=2|PinPropagationDelay=0.000000E+000
|RECORD=2|OwnerIndex=719|OwnerPartId=1|OwnerPartDisplayMode=1|FormalType=1|Electrical=4|PinConglomerate=34|PinLength=10|Location.X=470|Location.Y=420|Name=1|Designator=1|PinPropagationDelay=0.000000E+000
|RECORD=14|OwnerIndex=719|IsNotAccesible=T|IndexInSheet=2|OwnerPartId=1|OwnerPartDisplayMode=1|Location.X=470|Location.Y=416|Corner.X=490|Corner.Y=424|LineWidth=1|Color=16711680|AreaColor=11599871
|RECORD=2|OwnerIndex=719|OwnerPartId=1|FormalType=1|Electrical=4|PinConglomerate=32|PinLength=10|Location.X=490|Location.Y=420|Name=2|Designator=2|PinPropagationDelay=0.000000E+000
|RECORD=2|OwnerIndex=719|OwnerPartId=1|FormalType=1|Electrical=4|PinConglomerate=34|PinLength=10|Location.X=470|Location.Y=420|Name=1|Designator=1|PinPropagationDelay=0.000000E+000
|RECORD=6|OwnerIndex=719|IsNotAccesible=T|IndexInSheet=5|OwnerPartId=1|LineWidth=1|Color=16711680|LocationCount=10|X1=490|Y1=420|X2=486|Y2=420|X3=485|Y3=418|X4=483|Y4=422|X5=481|Y5=418|X6=479|Y6=422|X7=477|Y7=418|X8=475|Y8=422|X9=474|Y9=420|X10=470|Y10=420
|RECORD=41|OwnerIndex=719|IndexInSheet=6|OwnerPartId=-1|Location.X=458|Location.Y=433|Color=8388608|FontID=1|IsHidden=T|Text=CRCW040227R0FKED|Name=Part Number
|RECORD=41|OwnerIndex=719|IndexInSheet=7|OwnerPartId=-1|Location.X=458|Location.Y=433|Color=8388608|FontID=1|IsHidden=T|Text=Vishay Dale|Name=Manufacturer
|RECORD=34|OwnerIndex=719|IndexInSheet=-1|OwnerPartId=-1|Location.X=450|Location.Y=420|Color=8388608|FontID=1|Text=R164|Name=Designator|ReadOnlyState=1
|RECORD=41|OwnerIndex=719|IndexInSheet=-1|OwnerPartId=-1|Location.X=470|Location.Y=420|Color=8388608|FontID=1|Text=DNI_27_1%_0402|Name=Comment
|RECORD=44|OwnerIndex=719
|RECORD=45|OwnerIndex=734|IndexInSheet=-1|Description=Chip Resistor, 2-Leads, Body 1.00x0.50mm, IPC Medium Density|UseComponentLibrary=T|ModelName=RESC1005X40X25NL05T05|ModelType=PCBLIB|DatafileCount=1|ModelDatafileEntity0=RESC1005X40X25NL05T05|ModelDatafileKind0=PCBLib|IsCurrent=T|DatalinksLocked=T|DatabaseDatalinksLocked=T
|RECORD=46|OwnerIndex=735
|RECORD=48|OwnerIndex=735
|RECORD=41|OwnerIndex=737|IndexInSheet=-1|OwnerPartId=-1|Color=8388608|FontID=1|IsHidden=T|Text=2D|Name=Available Preview Images
|RECORD=45|OwnerIndex=734|IndexInSheet=-1|Description=Chip Resistor, 2-Leads, Body 1.00x0.50mm, IPC High Density|UseComponentLibrary=T|ModelName=RESC1005X40X25LL05T05|ModelType=PCBLIB|DatafileCount=1|ModelDatafileEntity0=RESC1005X40X25LL05T05|ModelDatafileKind0=PCBLib|DatalinksLocked=T|DatabaseDatalinksLocked=T
|RECORD=46|OwnerIndex=739
|RECORD=48|OwnerIndex=739
|RECORD=41|OwnerIndex=741|IndexInSheet=-1|OwnerPartId=-1|Color=8388608|FontID=1|IsHidden=T|Text=2D|Name=Available Preview Images
|RECORD=45|OwnerIndex=734|IndexInSheet=-1|Description=Chip Resistor, 2-Leads, Body 1.00x0.50mm, IPC Low Density|UseComponentLibrary=T|ModelName=RESC1005X40X25ML05T05|ModelType=PCBLIB|DatafileCount=1|ModelDatafileEntity0=RESC1005X40X25ML05T05|ModelDatafileKind0=PCBLib|DatalinksLocked=T|DatabaseDatalinksLocked=T
|RECORD=46|OwnerIndex=743
|RECORD=48|OwnerIndex=743
|RECORD=41|OwnerIndex=745|IndexInSheet=-1|OwnerPartId=-1|Color=8388608|FontID=1|IsHidden=T|Text=2D|Name=Available Preview Images
|RECORD=17|IndexInSheet=66|OwnerPartId=-1|ShowNetName=T|Location.X=700|Location.Y=620|Color=255|FontID=1|Text=GPS1_TX|IsCrossSheetConnector=T
|RECORD=17|IndexInSheet=67|OwnerPartId=-1|ShowNetName=T|Location.X=420|Location.Y=410|Orientation=2|Color=255|FontID=1|Text=M2_GPS1_TP2|IsCrossSheetConnector=T
|RECORD=17|IndexInSheet=68|OwnerPartId=-1|ShowNetName=T|Location.X=420|Location.Y=420|Orientation=2|Color=255|FontID=1|Text=M2_GPS1_TP1|IsCrossSheetConnector=T
|RECORD=17|IndexInSheet=69|OwnerPartId=-1|ShowNetName=T|Location.X=420|Location.Y=430|Orientation=2|Color=255|FontID=1|Text=M2_GPS1_RX|IsCrossSheetConnector=T
|RECORD=17|IndexInSheet=70|OwnerPartId=-1|ShowNetName=T|Location.X=420|Location.Y=440|Orientation=2|Color=255|FontID=1|Text=M2_GPS1_TX|IsCrossSheetConnector=T
|RECORD=17|IndexInSheet=71|OwnerPartId=-1|ShowNetName=T|Location.X=520|Location.Y=270|Color=255|FontID=1|Text=GPS1_PIN11|IsCrossSheetConnector=T
|RECORD=17|IndexInSheet=72|OwnerPartId=-1|ShowNetName=T|Location.X=520|Location.Y=230|Color=255|FontID=1|Text=GPS1_PIN12|IsCrossSheetConnector=T
|RECORD=17|IndexInSheet=73|OwnerPartId=-1|ShowNetName=T|Location.X=150|Location.Y=250|Orientation=2|Color=255|FontID=1|Text=M2_GPS1_PIN11|IsCrossSheetConnector=T
|RECORD=17|IndexInSheet=74|OwnerPartId=-1|ShowNetName=T|Location.X=150|Location.Y=210|Orientation=2|Color=255|FontID=1|Text=M2_GPS1_PIN12|IsCrossSheetConnector=T
|RECORD=17|IndexInSheet=75|OwnerPartId=-1|ShowNetName=T|Location.X=650|Location.Y=340|Color=255|FontID=1|Text=RCB_GPS1_PIN11|IsCrossSheetConnector=T
|RECORD=17|IndexInSheet=76|OwnerPartId=-1|ShowNetName=T|Location.X=650|Location.Y=330|Color=255|FontID=1|Text=M2_GPS1_PIN11|IsCrossSheetConnector=T
|RECORD=17|IndexInSheet=77|OwnerPartId=-1|ShowNetName=T|Location.X=650|Location.Y=320|Color=255|FontID=1|Text=RCB_GPS1_PIN12|IsCrossSheetConnector=T
|RECORD=17|IndexInSheet=78|OwnerPartId=-1|ShowNetName=T|Location.X=650|Location.Y=310|Color=255|FontID=1|Text=M2_GPS1_PIN12|IsCrossSheetConnector=T
|RECORD=17|IndexInSheet=79|OwnerPartId=-1|ShowNetName=T|Location.X=160|Location.Y=630|Orientation=2|Color=255|FontID=1|Text=RCB_GPS1_TX|IsCrossSheetConnector=T
|RECORD=17|IndexInSheet=80|OwnerPartId=-1|ShowNetName=T|Location.X=570|Location.Y=610|Color=255|FontID=1|Text=M2_GPS1_TX|IsCrossSheetConnector=T
|RECORD=17|IndexInSheet=81|OwnerPartId=-1|ShowNetName=T|Location.X=700|Location.Y=540|Color=255|FontID=1|Text=GPS1_RX|IsCrossSheetConnector=T
|RECORD=17|IndexInSheet=82|OwnerPartId=-1|ShowNetName=T|Location.X=700|Location.Y=550|Color=255|FontID=1|Text=GPS1_TP1|IsCrossSheetConnector=T
|RECORD=17|IndexInSheet=83|OwnerPartId=-1|ShowNetName=T|Location.X=700|Location.Y=580|Color=255|FontID=1|Text=GPS1_TP2|IsCrossSheetConnector=T
|RECORD=17|IndexInSheet=84|OwnerPartId=-1|ShowNetName=T|Location.X=150|Location.Y=600|Orientation=2|Color=255|FontID=1|Text=RCB_GPS1_RX|IsCrossSheetConnector=T
|RECORD=17|IndexInSheet=85|OwnerPartId=-1|ShowNetName=T|Location.X=560|Location.Y=560|Color=255|FontID=1|Text=RCB_GPS1_TP1|IsCrossSheetConnector=T
|RECORD=17|IndexInSheet=86|OwnerPartId=-1|ShowNetName=T|Location.X=560|Location.Y=590|Color=255|FontID=1|Text=RCB_GPS1_TP2|IsCrossSheetConnector=T
|RECORD=17|IndexInSheet=87|OwnerPartId=-1|ShowNetName=T|Location.X=150|Location.Y=610|Orientation=2|Color=255|FontID=1|Text=M2_GPS1_RX|IsCrossSheetConnector=T
|RECORD=17|IndexInSheet=88|OwnerPartId=-1|ShowNetName=T|Location.X=150|Location.Y=580|Orientation=2|Color=255|FontID=1|Text=M2_GPS1_TP1|IsCrossSheetConnector=T
|RECORD=17|IndexInSheet=89|OwnerPartId=-1|ShowNetName=T|Location.X=560|Location.Y=570|Color=255|FontID=1|Text=M2_GPS1_TP2|IsCrossSheetConnector=T
|RECORD=1|LibReference=PI3A412ZHE|ComponentDescription=No Description Available|PartCount=2|DisplayModeCount=1|IndexInSheet=90|OwnerPartId=-1|Location.X=920|Location.Y=700|CurrentPartId=1|LibraryPath=*|SourceLibraryName=PI3A412ZHE.SchLib|TargetFileName=*|AreaColor=11599871|Color=128|PartIDLocked=T|DesignItemId=PI3A412ZHE|AllPinCount=17
|RECORD=41|OwnerIndex=771|OwnerPartId=1|Location.X=920|Location.Y=700|FontID=1|IsHidden=T|Text=Pericom|Name=Mfr_Name
|RECORD=41|OwnerIndex=771|IndexInSheet=1|OwnerPartId=1|Location.X=1030|Location.Y=740|FontID=1|IsHidden=T|Text=RefDes|Name=RefDes
|RECORD=41|OwnerIndex=771|IndexInSheet=2|OwnerPartId=1|Location.X=1030|Location.Y=730|FontID=1|IsHidden=T|Text=Type|Name=Type
|RECORD=2|OwnerIndex=771|OwnerPartId=1|FormalType=1|Electrical=4|PinConglomerate=58|PinLength=30|Location.X=950|Location.Y=700|Name=NC1|Designator=1|SwapIdPin=0|SwapIDPart=0Ž&Ž1|PinPropagationDelay=0.000000E+000
|RECORD=2|OwnerIndex=771|OwnerPartId=1|FormalType=1|PinConglomerate=58|PinLength=30|Location.X=950|Location.Y=690|Name=A0|Designator=2|SwapIdPin=0|SwapIDPart=0Ž&Ž2|PinPropagationDelay=0.000000E+000
|RECORD=2|OwnerIndex=771|OwnerPartId=1|FormalType=1|Electrical=4|PinConglomerate=58|PinLength=30|Location.X=950|Location.Y=680|Name=NO2|Designator=3|SwapIdPin=0|SwapIDPart=0Ž&Ž3|PinPropagationDelay=0.000000E+000
|RECORD=2|OwnerIndex=771|OwnerPartId=1|FormalType=1|Electrical=4|PinConglomerate=58|PinLength=30|Location.X=950|Location.Y=670|Name=NC2|Designator=5|SwapIdPin=0|SwapIDPart=0Ž&Ž4|PinPropagationDelay=0.000000E+000
|RECORD=2|OwnerIndex=771|OwnerPartId=1|FormalType=1|Electrical=7|PinConglomerate=58|PinLength=30|Location.X=950|Location.Y=660|Name=GND|Designator=6|SwapIdPin=0|SwapIDPart=0Ž&Ž5|PinPropagationDelay=0.000000E+000
|RECORD=2|OwnerIndex=771|OwnerPartId=1|FormalType=1|Electrical=4|PinConglomerate=58|PinLength=30|Location.X=950|Location.Y=650|Name=NO3|Designator=7|SwapIdPin=0|SwapIDPart=0Ž&Ž6|PinPropagationDelay=0.000000E+000
|RECORD=2|OwnerIndex=771|OwnerPartId=1|FormalType=1|PinConglomerate=58|PinLength=30|Location.X=950|Location.Y=640|Name=A1|Designator=10|SwapIdPin=0|SwapIDPart=0Ž&Ž7|PinPropagationDelay=0.000000E+000
|RECORD=2|OwnerIndex=771|OwnerPartId=1|FormalType=1|Electrical=2|PinConglomerate=56|PinLength=30|Location.X=1110|Location.Y=610|Name=COM2|Designator=4|SwapIdPin=0|SwapIDPart=0Ž&Ž8|PinPropagationDelay=0.000000E+000
|RECORD=2|OwnerIndex=771|OwnerPartId=1|FormalType=1|Electrical=2|PinConglomerate=56|PinLength=30|Location.X=1110|Location.Y=620|Name=COM3|Designator=8|SwapIdPin=0|SwapIDPart=0Ž&Ž9|PinPropagationDelay=0.000000E+000
|RECORD=2|OwnerIndex=771|OwnerPartId=1|FormalType=1|Electrical=4|PinConglomerate=56|PinLength=30|Location.X=1110|Location.Y=630|Name=NC3|Designator=9|SwapIdPin=0|SwapIDPart=0Ž&Ž10|PinPropagationDelay=0.000000E+000
|RECORD=2|OwnerIndex=771|OwnerPartId=1|FormalType=1|Electrical=4|PinConglomerate=56|PinLength=30|Location.X=1110|Location.Y=640|Name=NO4|Designator=11|SwapIdPin=0|SwapIDPart=0Ž&Ž11|PinPropagationDelay=0.000000E+000
|RECORD=2|OwnerIndex=771|OwnerPartId=1|FormalType=1|Electrical=2|PinConglomerate=56|PinLength=30|Location.X=1110|Location.Y=650|Name=COM4|Designator=12|SwapIdPin=0|SwapIDPart=0Ž&Ž12|PinPropagationDelay=0.000000E+000
|RECORD=2|OwnerIndex=771|OwnerPartId=1|FormalType=1|Electrical=4|PinConglomerate=56|PinLength=30|Location.X=1110|Location.Y=660|Name=NC4|Designator=13|SwapIdPin=0|SwapIDPart=0Ž&Ž13|PinPropagationDelay=0.000000E+000
|RECORD=2|OwnerIndex=771|OwnerPartId=1|FormalType=1|Electrical=7|PinConglomerate=56|PinLength=30|Location.X=1110|Location.Y=670|Name=VCC|Designator=14|SwapIdPin=0|SwapIDPart=0Ž&Ž14|PinPropagationDelay=0.000000E+000
|RECORD=2|OwnerIndex=771|OwnerPartId=1|FormalType=1|Electrical=4|PinConglomerate=56|PinLength=30|Location.X=1110|Location.Y=680|Name=NO1|Designator=15|SwapIdPin=0|SwapIDPart=0Ž&Ž15|PinPropagationDelay=0.000000E+000
|RECORD=2|OwnerIndex=771|OwnerPartId=1|FormalType=1|Electrical=2|PinConglomerate=56|PinLength=30|Location.X=1110|Location.Y=690|Name=COM1|Designator=16|SwapIdPin=0|SwapIDPart=0Ž&Ž16|PinPropagationDelay=0.000000E+000
|RECORD=2|OwnerIndex=771|OwnerPartId=1|FormalType=1|Electrical=4|PinConglomerate=56|PinLength=30|Location.X=1110|Location.Y=700|Name=17|Designator=17|SwapIdPin=0|SwapIDPart=0Ž&Ž17|PinPropagationDelay=0.000000E+000
|RECORD=13|OwnerIndex=771|IsNotAccesible=T|IndexInSheet=20|OwnerPartId=1|Location.X=947|Location.X_Frac=95000|Location.Y=690|Corner.X=943|Corner.X_Frac=85000|Corner.Y=692|Corner.Y_Frac=5000|LineWidth=1
|RECORD=13|OwnerIndex=771|IsNotAccesible=T|IndexInSheet=21|OwnerPartId=1|Location.X=947|Location.X_Frac=95000|Location.Y=690|Corner.X=943|Corner.X_Frac=85000|Corner.Y=687|Corner.Y_Frac=95000|LineWidth=1
|RECORD=13|OwnerIndex=771|IsNotAccesible=T|IndexInSheet=22|OwnerPartId=1|Location.X=947|Location.X_Frac=95000|Location.Y=640|Corner.X=943|Corner.X_Frac=85000|Corner.Y=642|Corner.Y_Frac=5000|LineWidth=1
|RECORD=13|OwnerIndex=771|IsNotAccesible=T|IndexInSheet=23|OwnerPartId=1|Location.X=947|Location.X_Frac=95000|Location.Y=640|Corner.X=943|Corner.X_Frac=85000|Corner.Y=637|Corner.Y_Frac=95000|LineWidth=1
|RECORD=13|OwnerIndex=771|IsNotAccesible=T|IndexInSheet=24|OwnerPartId=1|Location.X=1112|Location.X_Frac=5000|Location.Y=612|Location.Y_Frac=5000|Corner.X=1116|Corner.X_Frac=15000|Corner.Y=610|LineWidth=1
|RECORD=13|OwnerIndex=771|IsNotAccesible=T|IndexInSheet=25|OwnerPartId=1|Location.X=1112|Location.X_Frac=5000|Location.Y=607|Location.Y_Frac=95000|Corner.X=1116|Corner.X_Frac=15000|Corner.Y=610|LineWidth=1
|RECORD=13|OwnerIndex=771|IsNotAccesible=T|IndexInSheet=26|OwnerPartId=1|Location.X=1112|Location.X_Frac=5000|Location.Y=622|Location.Y_Frac=5000|Corner.X=1116|Corner.X_Frac=15000|Corner.Y=620|LineWidth=1
|RECORD=13|OwnerIndex=771|IsNotAccesible=T|IndexInSheet=27|OwnerPartId=1|Location.X=1112|Location.X_Frac=5000|Location.Y=617|Location.Y_Frac=95000|Corner.X=1116|Corner.X_Frac=15000|Corner.Y=620|LineWidth=1
|RECORD=13|OwnerIndex=771|IsNotAccesible=T|IndexInSheet=28|OwnerPartId=1|Location.X=1112|Location.X_Frac=5000|Location.Y=652|Location.Y_Frac=5000|Corner.X=1116|Corner.X_Frac=15000|Corner.Y=650|LineWidth=1
|RECORD=13|OwnerIndex=771|IsNotAccesible=T|IndexInSheet=29|OwnerPartId=1|Location.X=1112|Location.X_Frac=5000|Location.Y=647|Location.Y_Frac=95000|Corner.X=1116|Corner.X_Frac=15000|Corner.Y=650|LineWidth=1
|RECORD=13|OwnerIndex=771|IsNotAccesible=T|IndexInSheet=30|OwnerPartId=1|Location.X=1112|Location.X_Frac=5000|Location.Y=692|Location.Y_Frac=5000|Corner.X=1116|Corner.X_Frac=15000|Corner.Y=690|LineWidth=1
|RECORD=13|OwnerIndex=771|IsNotAccesible=T|IndexInSheet=31|OwnerPartId=1|Location.X=1112|Location.X_Frac=5000|Location.Y=687|Location.Y_Frac=95000|Corner.X=1116|Corner.X_Frac=15000|Corner.Y=690|LineWidth=1
|RECORD=14|OwnerIndex=771|IsNotAccesible=T|IndexInSheet=32|OwnerPartId=1|Location.X=950|Location.Y=590|Corner.X=1110|Corner.Y=720|LineWidth=1|AreaColor=11599871|IsSolid=T|Transparent=T
|RECORD=34|OwnerIndex=771|IndexInSheet=-1|OwnerPartId=-1|Location.X=942|Location.X_Frac=85000|Location.Y=720|Color=8388608|FontID=1|Text=U28|Name=Designator|ReadOnlyState=1
|RECORD=41|OwnerIndex=771|IndexInSheet=-1|OwnerPartId=-1|Location.X=942|Location.X_Frac=85000|Location.Y=580|Color=8388608|FontID=1|Text=PI3A412ZHE|Name=Comment
|RECORD=44|OwnerIndex=771
|RECORD=45|OwnerIndex=824|IndexInSheet=-1|ModelName=ZH16_PER|ModelType=PCBLIB|DatafileCount=1|ModelDatafileEntity0=ZH16_PER|ModelDatafileKind0=PCBLIB|IsCurrent=T
|RECORD=46|OwnerIndex=825
|RECORD=48|OwnerIndex=825
|RECORD=1|LibReference=b4654b650e69147ec39a6b967a45e02|ComponentDescription=General Purpose Ceramic Capacitor, 0402, 100nF, 10%, X7R, 15%, 25V|PartCount=2|DisplayModeCount=1|IndexInSheet=91|OwnerPartId=-1|Location.X=1280|Location.Y=770|CurrentPartId=1|LibraryPath=*|SourceLibraryName=Altium Content Vault|TargetFileName=*|AreaColor=11599871|Color=128|PartIDLocked=T|DesignItemId=CMP-2008-02519-2|AllPinCount=2
|RECORD=2|OwnerIndex=828|OwnerPartId=1|Electrical=4|PinConglomerate=49|PinLength=7|Location.X=1280|Location.Y=763|Name=1|Designator=1|PinPropagationDelay=0.000000E+000
|RECORD=2|OwnerIndex=828|OwnerPartId=1|Electrical=4|PinConglomerate=51|PinLength=6|Location.X=1280|Location.Y=756|Name=2|Designator=2|PinPropagationDelay=0.000000E+000
|RECORD=13|OwnerIndex=828|IsNotAccesible=T|IndexInSheet=2|OwnerPartId=1|Location.X=1290|Location.Y=763|Corner.X=1270|Corner.Y=763|LineWidth=1|Color=16711680
|RECORD=13|OwnerIndex=828|IsNotAccesible=T|IndexInSheet=3|OwnerPartId=1|Location.X=1290|Location.Y=757|Corner.X=1270|Corner.Y=757|LineWidth=1|Color=16711680
|RECORD=13|OwnerIndex=828|IsNotAccesible=T|IndexInSheet=4|OwnerPartId=1|Location.X=1280|Location.Y=763|Corner.X=1280|Corner.Y=766|LineWidth=1|Color=16711680
|RECORD=13|OwnerIndex=828|IsNotAccesible=T|IndexInSheet=5|OwnerPartId=1|Location.X=1280|Location.Y=756|Corner.X=1280|Corner.Y=755|LineWidth=1|Color=16711680
|RECORD=41|OwnerIndex=828|IndexInSheet=6|OwnerPartId=-1|Location.X=1269|Location.Y=772|Color=8388608|FontID=1|IsHidden=T|Text=1|Name=Package Quantity
|RECORD=41|OwnerIndex=828|IndexInSheet=7|OwnerPartId=-1|Location.X=1269|Location.Y=772|Color=8388608|FontID=1|IsHidden=T|Text=100nF|Name=Capacitance
|RECORD=41|OwnerIndex=828|IndexInSheet=8|OwnerPartId=-1|Location.X=1269|Location.Y=772|Color=8388608|FontID=1|IsHidden=T|Text=-55°C|Name=Min Operating Temperature
|RECORD=41|OwnerIndex=828|IndexInSheet=9|OwnerPartId=-1|Location.X=1269|Location.Y=772|Color=8388608|FontID=1|IsHidden=T|Text=25V|Name=Voltage
|RECORD=41|OwnerIndex=828|IndexInSheet=10|OwnerPartId=-1|Location.X=1269|Location.Y=772|Color=8388608|FontID=1|IsHidden=T|Text=25V|Name=Voltage Rating
|RECORD=41|OwnerIndex=828|IndexInSheet=11|OwnerPartId=-1|Location.X=1269|Location.Y=772|Color=8388608|FontID=1|IsHidden=T|Text=Flat|Name=Construction
|RECORD=41|OwnerIndex=828|IndexInSheet=12|OwnerPartId=-1|Location.X=1269|Location.Y=772|Color=8388608|FontID=1|IsHidden=T|Text=125°C|Name=Max Operating Temperature
|RECORD=41|OwnerIndex=828|IndexInSheet=13|OwnerPartId=-1|Location.X=1269|Location.Y=772|Color=8388608|FontID=1|IsHidden=T|Text=No|Name=Radiation Hardening
|RECORD=41|OwnerIndex=828|IndexInSheet=14|OwnerPartId=-1|Location.X=1269|Location.Y=772|Color=8388608|FontID=1|IsHidden=T|Text=0.5mm|Name=Depth
|RECORD=41|OwnerIndex=828|IndexInSheet=15|OwnerPartId=-1|Location.X=1269|Location.Y=772|Color=8388608|FontID=1|IsHidden=T|Text=0.022inch|Name=Thickness
|RECORD=41|OwnerIndex=828|IndexInSheet=16|OwnerPartId=-1|Location.X=1269|Location.Y=772|Color=8388608|FontID=1|IsHidden=T|Text=25V|Name=Voltage Rating (DC)
|RECORD=41|OwnerIndex=828|IndexInSheet=17|OwnerPartId=-1|Location.X=1269|Location.Y=772|Color=8388608|FontID=1|IsHidden=T|Text=2|Name=Number of Pins
|RECORD=41|OwnerIndex=828|IndexInSheet=18|OwnerPartId=-1|Location.X=1269|Location.Y=772|Color=8388608|FontID=1|IsHidden=T|Text=Lead Free|Name=Lead Free
|RECORD=41|OwnerIndex=828|IndexInSheet=19|OwnerPartId=-1|Location.X=1269|Location.Y=772|Color=8388608|FontID=1|IsHidden=T|Text=-|Name=Series
|RECORD=41|OwnerIndex=828|IndexInSheet=20|OwnerPartId=-1|Location.X=1269|Location.Y=772|Color=8388608|FontID=1|IsHidden=T|Text=No SVHC|Name=REACH SVHC
|RECORD=41|OwnerIndex=828|IndexInSheet=21|OwnerPartId=-1|Location.X=1269|Location.Y=772|Color=8388608|FontID=1|IsHidden=T|Text=1mm|Name=Length
|RECORD=41|OwnerIndex=828|IndexInSheet=22|OwnerPartId=-1|Location.X=1269|Location.Y=772|Color=8388608|FontID=1|IsHidden=T|Text=X7R|Name=Dielectric
|RECORD=41|OwnerIndex=828|IndexInSheet=23|OwnerPartId=-1|Location.X=1269|Location.Y=772|Color=8388608|FontID=1|IsHidden=T|Text=Yes|Name=RoHS Compliant
|RECORD=41|OwnerIndex=828|IndexInSheet=24|OwnerPartId=-1|Location.X=1269|Location.Y=772|Color=8388608|FontID=1|IsHidden=T|Text=Surface Mount|Name=Mount
|RECORD=41|OwnerIndex=828|IndexInSheet=25|OwnerPartId=-1|Location.X=1269|Location.Y=772|Color=8388608|FontID=1|IsHidden=T|Text=Tape and Reel|Name=Packaging
|RECORD=41|OwnerIndex=828|IndexInSheet=26|OwnerPartId=-1|Location.X=1269|Location.Y=772|Color=8388608|FontID=1|IsHidden=T|Text=0402|Name=Case/Package
|RECORD=41|OwnerIndex=828|IndexInSheet=27|OwnerPartId=-1|Location.X=1269|Location.Y=772|Color=8388608|FontID=1|IsHidden=T|Text=0402|Name=Case Code (Imperial)
|RECORD=41|OwnerIndex=828|IndexInSheet=28|OwnerPartId=-1|Location.X=1269|Location.Y=772|Color=8388608|FontID=1|IsHidden=T|Text=SMD/SMT|Name=Termination
|RECORD=41|OwnerIndex=828|IndexInSheet=29|OwnerPartId=-1|Location.X=1269|Location.Y=772|Color=8388608|FontID=1|IsHidden=T|Text=0.02inch|Name=Width
|RECORD=41|OwnerIndex=828|IndexInSheet=30|OwnerPartId=-1|Location.X=1269|Location.Y=772|Color=8388608|FontID=1|IsHidden=T|Text=1005|Name=Case Code (Metric)
|RECORD=41|OwnerIndex=828|IndexInSheet=31|OwnerPartId=-1|Location.X=1269|Location.Y=772|Color=8388608|FontID=1|IsHidden=T|Text=10%|Name=Tolerance
|RECORD=34|OwnerIndex=828|IndexInSheet=-1|OwnerPartId=-1|Location.X=1291|Location.Y=757|Color=8388608|FontID=1|Text=C106|Name=Designator|ReadOnlyState=1
|RECORD=41|OwnerIndex=828|IndexInSheet=-1|OwnerPartId=1|Location.X=1291|Location.Y=747|Color=8388608|FontID=1|Text=0.1uF_25V_0402|Name=Comment
|RECORD=44|OwnerIndex=828
|RECORD=45|OwnerIndex=865|IndexInSheet=-1|UseComponentLibrary=T|ModelName=FP-0402-L_1_0_1-W_0_5_0_1-IPC_C|ModelType=PCBLIB|DatafileCount=1|ModelDatafileEntity0=FP-0402-L_1_0_1-W_0_5_0_1-IPC_C|ModelDatafileKind0=PCBLib|IsCurrent=T|DatalinksLocked=T|DatabaseDatalinksLocked=T
|RECORD=46|OwnerIndex=866
|RECORD=48|OwnerIndex=866
|RECORD=45|OwnerIndex=865|IndexInSheet=-1|UseComponentLibrary=T|ModelName=FP-0402-L_1_0_1-W_0_5_0_1-IPC_B|ModelType=PCBLIB|DatafileCount=1|ModelDatafileEntity0=FP-0402-L_1_0_1-W_0_5_0_1-IPC_B|ModelDatafileKind0=PCBLib|DatalinksLocked=T|DatabaseDatalinksLocked=T
|RECORD=46|OwnerIndex=869
|RECORD=48|OwnerIndex=869
|RECORD=45|OwnerIndex=865|IndexInSheet=-1|UseComponentLibrary=T|ModelName=FP-0402-L_1_0_1-W_0_5_0_1-MFG|ModelType=PCBLIB|DatafileCount=1|ModelDatafileEntity0=FP-0402-L_1_0_1-W_0_5_0_1-MFG|ModelDatafileKind0=PCBLib|DatalinksLocked=T|DatabaseDatalinksLocked=T
|RECORD=46|OwnerIndex=872
|RECORD=48|OwnerIndex=872
|RECORD=45|OwnerIndex=865|IndexInSheet=-1|UseComponentLibrary=T|ModelName=FP-0402-L_1_0_1-W_0_5_0_1-IPC_A|ModelType=PCBLIB|DatafileCount=1|ModelDatafileEntity0=FP-0402-L_1_0_1-W_0_5_0_1-IPC_A|ModelDatafileKind0=PCBLib|DatalinksLocked=T|DatabaseDatalinksLocked=T
|RECORD=46|OwnerIndex=875
|RECORD=48|OwnerIndex=875
|RECORD=17|IndexInSheet=92|OwnerPartId=-1|ShowNetName=T|Location.X=1280|Location.Y=820|Orientation=1|Color=128|FontID=1|Text=+3.3V
|RECORD=17|IndexInSheet=93|OwnerPartId=-1|Style=4|ShowNetName=T|Location.X=1280|Location.Y=730|Orientation=3|Color=128|FontID=1|Text=GND
|RECORD=17|IndexInSheet=94|OwnerPartId=-1|ShowNetName=T|Location.X=850|Location.Y=690|Orientation=2|Color=255|FontID=1|Text=DIP_SW_GPS2_SEL|IsCrossSheetConnector=T
|RECORD=17|IndexInSheet=95|OwnerPartId=-1|Style=4|ShowNetName=T|Location.X=900|Location.Y=610|Orientation=3|Color=128|FontID=1|Text=GND
|RECORD=1|LibReference=RES|PartCount=2|DisplayModeCount=2|IndexInSheet=96|OwnerPartId=-1|Location.X=1180|Location.Y=620|CurrentPartId=1|SourceLibraryName=Altium Content Vault|TargetFileName=*|AreaColor=11599871|Color=128|PartIDLocked=F|DesignItemId=CMP-2002-07709-1|AllPinCount=2
|RECORD=2|OwnerIndex=882|OwnerPartId=1|OwnerPartDisplayMode=1|FormalType=1|Electrical=4|PinConglomerate=32|PinLength=10|Location.X=1200|Location.Y=610|Name=2|Designator=2|PinPropagationDelay=0.000000E+000
|RECORD=2|OwnerIndex=882|OwnerPartId=1|OwnerPartDisplayMode=1|FormalType=1|Electrical=4|PinConglomerate=34|PinLength=10|Location.X=1180|Location.Y=610|Name=1|Designator=1|PinPropagationDelay=0.000000E+000
|RECORD=14|OwnerIndex=882|IsNotAccesible=T|IndexInSheet=2|OwnerPartId=1|OwnerPartDisplayMode=1|Location.X=1180|Location.Y=606|Corner.X=1200|Corner.Y=614|LineWidth=1|Color=16711680|AreaColor=11599871
|RECORD=2|OwnerIndex=882|OwnerPartId=1|FormalType=1|Electrical=4|PinConglomerate=32|PinLength=10|Location.X=1200|Location.Y=610|Name=2|Designator=2|PinPropagationDelay=0.000000E+000
|RECORD=2|OwnerIndex=882|OwnerPartId=1|FormalType=1|Electrical=4|PinConglomerate=34|PinLength=10|Location.X=1180|Location.Y=610|Name=1|Designator=1|PinPropagationDelay=0.000000E+000
|RECORD=6|OwnerIndex=882|IsNotAccesible=T|IndexInSheet=5|OwnerPartId=1|LineWidth=1|Color=16711680|LocationCount=10|X1=1200|Y1=610|X2=1196|Y2=610|X3=1195|Y3=608|X4=1193|Y4=612|X5=1191|Y5=608|X6=1189|Y6=612|X7=1187|Y7=608|X8=1185|Y8=612|X9=1184|Y9=610|X10=1180|Y10=610
|RECORD=41|OwnerIndex=882|IndexInSheet=6|OwnerPartId=-1|Location.X=1168|Location.Y=623|Color=8388608|FontID=1|IsHidden=T|Text=Yageo / Phycomp|Name=Manufacturer
|RECORD=41|OwnerIndex=882|IndexInSheet=7|OwnerPartId=-1|Location.X=1168|Location.Y=623|Color=8388608|FontID=1|IsHidden=T|Text=RC0402FR-0749R9L|Name=Part Number
|RECORD=34|OwnerIndex=882|IndexInSheet=-1|OwnerPartId=-1|Location.X=1160|Location.Y=610|Color=8388608|FontID=1|Text=R146|Name=Designator|ReadOnlyState=1
|RECORD=41|OwnerIndex=882|IndexInSheet=-1|OwnerPartId=-1|Location.X=1200|Location.Y=610|Color=8388608|FontID=1|Text=49.9_1%_0402|Name=Comment
|RECORD=44|OwnerIndex=882
|RECORD=45|OwnerIndex=897|IndexInSheet=-1|Description=Chip Resistor, 2-Leads, Body 1.00x0.50mm, IPC High Density|UseComponentLibrary=T|ModelName=RESC1005X40X25LL05T10|ModelType=PCBLIB|DatafileCount=1|ModelDatafileEntity0=RESC1005X40X25LL05T10|ModelDatafileKind0=PCBLib|IsCurrent=T|DatalinksLocked=T|DatabaseDatalinksLocked=T
|RECORD=46|OwnerIndex=898
|RECORD=48|OwnerIndex=898
|RECORD=41|OwnerIndex=900|IndexInSheet=-1|OwnerPartId=-1|Color=8388608|FontID=1|IsHidden=T|Text=2D|Name=Available Preview Images
|RECORD=45|OwnerIndex=897|IndexInSheet=-1|Description=Chip Resistor, 2-Leads, Body 1.00x0.50mm, IPC Low Density|UseComponentLibrary=T|ModelName=RESC1005X40X25ML05T10|ModelType=PCBLIB|DatafileCount=1|ModelDatafileEntity0=RESC1005X40X25ML05T10|ModelDatafileKind0=PCBLib|DatalinksLocked=T|DatabaseDatalinksLocked=T
|RECORD=46|OwnerIndex=902
|RECORD=48|OwnerIndex=902
|RECORD=41|OwnerIndex=904|IndexInSheet=-1|OwnerPartId=-1|Color=8388608|FontID=1|IsHidden=T|Text=2D|Name=Available Preview Images
|RECORD=45|OwnerIndex=897|IndexInSheet=-1|Description=Chip Resistor, 2-Leads, Body 1.00x0.50mm, IPC Medium Density|UseComponentLibrary=T|ModelName=RESC1005X40X25NL05T10|ModelType=PCBLIB|DatafileCount=1|ModelDatafileEntity0=RESC1005X40X25NL05T10|ModelDatafileKind0=PCBLib|DatalinksLocked=T|DatabaseDatalinksLocked=T
|RECORD=46|OwnerIndex=906
|RECORD=48|OwnerIndex=906
|RECORD=41|OwnerIndex=908|IndexInSheet=-1|OwnerPartId=-1|Color=8388608|FontID=1|IsHidden=T|Text=2D|Name=Available Preview Images
|RECORD=1|LibReference=RES|PartCount=2|DisplayModeCount=2|IndexInSheet=97|OwnerPartId=-1|Location.X=1220|Location.Y=630|CurrentPartId=1|SourceLibraryName=Altium Content Vault|TargetFileName=*|AreaColor=11599871|Color=128|PartIDLocked=F|DesignItemId=CMP-2002-07709-1|AllPinCount=2
|RECORD=2|OwnerIndex=910|OwnerPartId=1|OwnerPartDisplayMode=1|FormalType=1|Electrical=4|PinConglomerate=32|PinLength=10|Location.X=1240|Location.Y=620|Name=2|Designator=2|PinPropagationDelay=0.000000E+000
|RECORD=2|OwnerIndex=910|OwnerPartId=1|OwnerPartDisplayMode=1|FormalType=1|Electrical=4|PinConglomerate=34|PinLength=10|Location.X=1220|Location.Y=620|Name=1|Designator=1|PinPropagationDelay=0.000000E+000
|RECORD=14|OwnerIndex=910|IsNotAccesible=T|IndexInSheet=2|OwnerPartId=1|OwnerPartDisplayMode=1|Location.X=1220|Location.Y=616|Corner.X=1240|Corner.Y=624|LineWidth=1|Color=16711680|AreaColor=11599871
|RECORD=2|OwnerIndex=910|OwnerPartId=1|FormalType=1|Electrical=4|PinConglomerate=32|PinLength=10|Location.X=1240|Location.Y=620|Name=2|Designator=2|PinPropagationDelay=0.000000E+000
|RECORD=2|OwnerIndex=910|OwnerPartId=1|FormalType=1|Electrical=4|PinConglomerate=34|PinLength=10|Location.X=1220|Location.Y=620|Name=1|Designator=1|PinPropagationDelay=0.000000E+000
|RECORD=6|OwnerIndex=910|IsNotAccesible=T|IndexInSheet=5|OwnerPartId=1|LineWidth=1|Color=16711680|LocationCount=10|X1=1240|Y1=620|X2=1236|Y2=620|X3=1235|Y3=618|X4=1233|Y4=622|X5=1231|Y5=618|X6=1229|Y6=622|X7=1227|Y7=618|X8=1225|Y8=622|X9=1224|Y9=620|X10=1220|Y10=620
|RECORD=41|OwnerIndex=910|IndexInSheet=6|OwnerPartId=-1|Location.X=1208|Location.Y=633|Color=8388608|FontID=1|IsHidden=T|Text=Yageo / Phycomp|Name=Manufacturer
|RECORD=41|OwnerIndex=910|IndexInSheet=7|OwnerPartId=-1|Location.X=1208|Location.Y=633|Color=8388608|FontID=1|IsHidden=T|Text=RC0402FR-0749R9L|Name=Part Number
|RECORD=34|OwnerIndex=910|IndexInSheet=-1|OwnerPartId=-1|Location.X=1200|Location.Y=620|Color=8388608|FontID=1|Text=R145|Name=Designator|ReadOnlyState=1
|RECORD=41|OwnerIndex=910|IndexInSheet=-1|OwnerPartId=-1|Location.X=1240|Location.Y=620|Color=8388608|FontID=1|Text=49.9_1%_0402|Name=Comment
|RECORD=44|OwnerIndex=910
|RECORD=45|OwnerIndex=925|IndexInSheet=-1|Description=Chip Resistor, 2-Leads, Body 1.00x0.50mm, IPC High Density|UseComponentLibrary=T|ModelName=RESC1005X40X25LL05T10|ModelType=PCBLIB|DatafileCount=1|ModelDatafileEntity0=RESC1005X40X25LL05T10|ModelDatafileKind0=PCBLib|IsCurrent=T|DatalinksLocked=T|DatabaseDatalinksLocked=T
|RECORD=46|OwnerIndex=926
|RECORD=48|OwnerIndex=926
|RECORD=41|OwnerIndex=928|IndexInSheet=-1|OwnerPartId=-1|Color=8388608|FontID=1|IsHidden=T|Text=2D|Name=Available Preview Images
|RECORD=45|OwnerIndex=925|IndexInSheet=-1|Description=Chip Resistor, 2-Leads, Body 1.00x0.50mm, IPC Low Density|UseComponentLibrary=T|ModelName=RESC1005X40X25ML05T10|ModelType=PCBLIB|DatafileCount=1|ModelDatafileEntity0=RESC1005X40X25ML05T10|ModelDatafileKind0=PCBLib|DatalinksLocked=T|DatabaseDatalinksLocked=T
|RECORD=46|OwnerIndex=930
|RECORD=48|OwnerIndex=930
|RECORD=41|OwnerIndex=932|IndexInSheet=-1|OwnerPartId=-1|Color=8388608|FontID=1|IsHidden=T|Text=2D|Name=Available Preview Images
|RECORD=45|OwnerIndex=925|IndexInSheet=-1|Description=Chip Resistor, 2-Leads, Body 1.00x0.50mm, IPC Medium Density|UseComponentLibrary=T|ModelName=RESC1005X40X25NL05T10|ModelType=PCBLIB|DatafileCount=1|ModelDatafileEntity0=RESC1005X40X25NL05T10|ModelDatafileKind0=PCBLib|DatalinksLocked=T|DatabaseDatalinksLocked=T
|RECORD=46|OwnerIndex=934
|RECORD=48|OwnerIndex=934
|RECORD=41|OwnerIndex=936|IndexInSheet=-1|OwnerPartId=-1|Color=8388608|FontID=1|IsHidden=T|Text=2D|Name=Available Preview Images
|RECORD=1|LibReference=RES|PartCount=2|DisplayModeCount=2|IndexInSheet=98|OwnerPartId=-1|Location.X=1180|Location.Y=660|CurrentPartId=1|SourceLibraryName=Altium Content Vault|TargetFileName=*|AreaColor=11599871|Color=128|PartIDLocked=F|DesignItemId=CMP-2002-07709-1|AllPinCount=2
|RECORD=2|OwnerIndex=938|OwnerPartId=1|OwnerPartDisplayMode=1|FormalType=1|Electrical=4|PinConglomerate=32|PinLength=10|Location.X=1200|Location.Y=650|Name=2|Designator=2|PinPropagationDelay=0.000000E+000
|RECORD=2|OwnerIndex=938|OwnerPartId=1|OwnerPartDisplayMode=1|FormalType=1|Electrical=4|PinConglomerate=34|PinLength=10|Location.X=1180|Location.Y=650|Name=1|Designator=1|PinPropagationDelay=0.000000E+000
|RECORD=14|OwnerIndex=938|IsNotAccesible=T|IndexInSheet=2|OwnerPartId=1|OwnerPartDisplayMode=1|Location.X=1180|Location.Y=646|Corner.X=1200|Corner.Y=654|LineWidth=1|Color=16711680|AreaColor=11599871
|RECORD=2|OwnerIndex=938|OwnerPartId=1|FormalType=1|Electrical=4|PinConglomerate=32|PinLength=10|Location.X=1200|Location.Y=650|Name=2|Designator=2|PinPropagationDelay=0.000000E+000
|RECORD=2|OwnerIndex=938|OwnerPartId=1|FormalType=1|Electrical=4|PinConglomerate=34|PinLength=10|Location.X=1180|Location.Y=650|Name=1|Designator=1|PinPropagationDelay=0.000000E+000
|RECORD=6|OwnerIndex=938|IsNotAccesible=T|IndexInSheet=5|OwnerPartId=1|LineWidth=1|Color=16711680|LocationCount=10|X1=1200|Y1=650|X2=1196|Y2=650|X3=1195|Y3=648|X4=1193|Y4=652|X5=1191|Y5=648|X6=1189|Y6=652|X7=1187|Y7=648|X8=1185|Y8=652|X9=1184|Y9=650|X10=1180|Y10=650
|RECORD=41|OwnerIndex=938|IndexInSheet=6|OwnerPartId=-1|Location.X=1168|Location.Y=663|Color=8388608|FontID=1|IsHidden=T|Text=Yageo / Phycomp|Name=Manufacturer
|RECORD=41|OwnerIndex=938|IndexInSheet=7|OwnerPartId=-1|Location.X=1168|Location.Y=663|Color=8388608|FontID=1|IsHidden=T|Text=RC0402FR-0749R9L|Name=Part Number
|RECORD=34|OwnerIndex=938|IndexInSheet=-1|OwnerPartId=-1|Location.X=1160|Location.Y=650|Color=8388608|FontID=1|Text=R143|Name=Designator|ReadOnlyState=1
|RECORD=41|OwnerIndex=938|IndexInSheet=-1|OwnerPartId=-1|Location.X=1200|Location.Y=650|Color=8388608|FontID=1|Text=49.9_1%_0402|Name=Comment
|RECORD=44|OwnerIndex=938
|RECORD=45|OwnerIndex=953|IndexInSheet=-1|Description=Chip Resistor, 2-Leads, Body 1.00x0.50mm, IPC High Density|UseComponentLibrary=T|ModelName=RESC1005X40X25LL05T10|ModelType=PCBLIB|DatafileCount=1|ModelDatafileEntity0=RESC1005X40X25LL05T10|ModelDatafileKind0=PCBLib|IsCurrent=T|DatalinksLocked=T|DatabaseDatalinksLocked=T
|RECORD=46|OwnerIndex=954
|RECORD=48|OwnerIndex=954
|RECORD=41|OwnerIndex=956|IndexInSheet=-1|OwnerPartId=-1|Color=8388608|FontID=1|IsHidden=T|Text=2D|Name=Available Preview Images
|RECORD=45|OwnerIndex=953|IndexInSheet=-1|Description=Chip Resistor, 2-Leads, Body 1.00x0.50mm, IPC Low Density|UseComponentLibrary=T|ModelName=RESC1005X40X25ML05T10|ModelType=PCBLIB|DatafileCount=1|ModelDatafileEntity0=RESC1005X40X25ML05T10|ModelDatafileKind0=PCBLib|DatalinksLocked=T|DatabaseDatalinksLocked=T
|RECORD=46|OwnerIndex=958
|RECORD=48|OwnerIndex=958
|RECORD=41|OwnerIndex=960|IndexInSheet=-1|OwnerPartId=-1|Color=8388608|FontID=1|IsHidden=T|Text=2D|Name=Available Preview Images
|RECORD=45|OwnerIndex=953|IndexInSheet=-1|Description=Chip Resistor, 2-Leads, Body 1.00x0.50mm, IPC Medium Density|UseComponentLibrary=T|ModelName=RESC1005X40X25NL05T10|ModelType=PCBLIB|DatafileCount=1|ModelDatafileEntity0=RESC1005X40X25NL05T10|ModelDatafileKind0=PCBLib|DatalinksLocked=T|DatabaseDatalinksLocked=T
|RECORD=46|OwnerIndex=962
|RECORD=48|OwnerIndex=962
|RECORD=41|OwnerIndex=964|IndexInSheet=-1|OwnerPartId=-1|Color=8388608|FontID=1|IsHidden=T|Text=2D|Name=Available Preview Images
|RECORD=1|LibReference=RES|PartCount=2|DisplayModeCount=2|IndexInSheet=99|OwnerPartId=-1|Location.X=1180|Location.Y=700|CurrentPartId=1|SourceLibraryName=Altium Content Vault|TargetFileName=*|AreaColor=11599871|Color=128|PartIDLocked=F|DesignItemId=CMP-2002-07709-1|AllPinCount=2
|RECORD=2|OwnerIndex=966|OwnerPartId=1|OwnerPartDisplayMode=1|FormalType=1|Electrical=4|PinConglomerate=32|PinLength=10|Location.X=1200|Location.Y=690|Name=2|Designator=2|PinPropagationDelay=0.000000E+000
|RECORD=2|OwnerIndex=966|OwnerPartId=1|OwnerPartDisplayMode=1|FormalType=1|Electrical=4|PinConglomerate=34|PinLength=10|Location.X=1180|Location.Y=690|Name=1|Designator=1|PinPropagationDelay=0.000000E+000
|RECORD=14|OwnerIndex=966|IsNotAccesible=T|IndexInSheet=2|OwnerPartId=1|OwnerPartDisplayMode=1|Location.X=1180|Location.Y=686|Corner.X=1200|Corner.Y=694|LineWidth=1|Color=16711680|AreaColor=11599871
|RECORD=2|OwnerIndex=966|OwnerPartId=1|FormalType=1|Electrical=4|PinConglomerate=32|PinLength=10|Location.X=1200|Location.Y=690|Name=2|Designator=2|PinPropagationDelay=0.000000E+000
|RECORD=2|OwnerIndex=966|OwnerPartId=1|FormalType=1|Electrical=4|PinConglomerate=34|PinLength=10|Location.X=1180|Location.Y=690|Name=1|Designator=1|PinPropagationDelay=0.000000E+000
|RECORD=6|OwnerIndex=966|IsNotAccesible=T|IndexInSheet=5|OwnerPartId=1|LineWidth=1|Color=16711680|LocationCount=10|X1=1200|Y1=690|X2=1196|Y2=690|X3=1195|Y3=688|X4=1193|Y4=692|X5=1191|Y5=688|X6=1189|Y6=692|X7=1187|Y7=688|X8=1185|Y8=692|X9=1184|Y9=690|X10=1180|Y10=690
|RECORD=41|OwnerIndex=966|IndexInSheet=6|OwnerPartId=-1|Location.X=1168|Location.Y=703|Color=8388608|FontID=1|IsHidden=T|Text=Yageo / Phycomp|Name=Manufacturer
|RECORD=41|OwnerIndex=966|IndexInSheet=7|OwnerPartId=-1|Location.X=1168|Location.Y=703|Color=8388608|FontID=1|IsHidden=T|Text=RC0402FR-0749R9L|Name=Part Number
|RECORD=34|OwnerIndex=966|IndexInSheet=-1|OwnerPartId=-1|Location.X=1160|Location.Y=690|Color=8388608|FontID=1|Text=R142|Name=Designator|ReadOnlyState=1
|RECORD=41|OwnerIndex=966|IndexInSheet=-1|OwnerPartId=-1|Location.X=1200|Location.Y=690|Color=8388608|FontID=1|Text=49.9_1%_0402|Name=Comment
|RECORD=44|OwnerIndex=966
|RECORD=45|OwnerIndex=981|IndexInSheet=-1|Description=Chip Resistor, 2-Leads, Body 1.00x0.50mm, IPC High Density|UseComponentLibrary=T|ModelName=RESC1005X40X25LL05T10|ModelType=PCBLIB|DatafileCount=1|ModelDatafileEntity0=RESC1005X40X25LL05T10|ModelDatafileKind0=PCBLib|IsCurrent=T|DatalinksLocked=T|DatabaseDatalinksLocked=T
|RECORD=46|OwnerIndex=982
|RECORD=48|OwnerIndex=982
|RECORD=41|OwnerIndex=984|IndexInSheet=-1|OwnerPartId=-1|Color=8388608|FontID=1|IsHidden=T|Text=2D|Name=Available Preview Images
|RECORD=45|OwnerIndex=981|IndexInSheet=-1|Description=Chip Resistor, 2-Leads, Body 1.00x0.50mm, IPC Low Density|UseComponentLibrary=T|ModelName=RESC1005X40X25ML05T10|ModelType=PCBLIB|DatafileCount=1|ModelDatafileEntity0=RESC1005X40X25ML05T10|ModelDatafileKind0=PCBLib|DatalinksLocked=T|DatabaseDatalinksLocked=T
|RECORD=46|OwnerIndex=986
|RECORD=48|OwnerIndex=986
|RECORD=41|OwnerIndex=988|IndexInSheet=-1|OwnerPartId=-1|Color=8388608|FontID=1|IsHidden=T|Text=2D|Name=Available Preview Images
|RECORD=45|OwnerIndex=981|IndexInSheet=-1|Description=Chip Resistor, 2-Leads, Body 1.00x0.50mm, IPC Medium Density|UseComponentLibrary=T|ModelName=RESC1005X40X25NL05T10|ModelType=PCBLIB|DatafileCount=1|ModelDatafileEntity0=RESC1005X40X25NL05T10|ModelDatafileKind0=PCBLib|DatalinksLocked=T|DatabaseDatalinksLocked=T
|RECORD=46|OwnerIndex=990
|RECORD=48|OwnerIndex=990
|RECORD=41|OwnerIndex=992|IndexInSheet=-1|OwnerPartId=-1|Color=8388608|FontID=1|IsHidden=T|Text=2D|Name=Available Preview Images
|RECORD=17|IndexInSheet=100|OwnerPartId=-1|ShowNetName=T|Location.X=1130|Location.Y=540|Orientation=2|Color=255|FontID=1|Text=RCB_GPS2_TP2|IsCrossSheetConnector=T
|RECORD=17|IndexInSheet=101|OwnerPartId=-1|ShowNetName=T|Location.X=1130|Location.Y=550|Orientation=2|Color=255|FontID=1|Text=RCB_GPS2_TP1|IsCrossSheetConnector=T
|RECORD=17|IndexInSheet=102|OwnerPartId=-1|ShowNetName=T|Location.X=1130|Location.Y=560|Orientation=2|Color=255|FontID=1|Text=RCB_GPS2_RX|IsCrossSheetConnector=T
|RECORD=17|IndexInSheet=103|OwnerPartId=-1|ShowNetName=T|Location.X=1130|Location.Y=570|Orientation=2|Color=255|FontID=1|Text=RCB_GPS2_TX|IsCrossSheetConnector=T
|RECORD=17|IndexInSheet=104|OwnerPartId=-1|ShowNetName=T|Location.X=860|Location.Y=340|Orientation=2|Color=255|FontID=1|Text=RCB_GPS2_PIN11|IsCrossSheetConnector=T
|RECORD=17|IndexInSheet=105|OwnerPartId=-1|ShowNetName=T|Location.X=860|Location.Y=300|Orientation=2|Color=255|FontID=1|Text=RCB_GPS2_PIN12|IsCrossSheetConnector=T
|RECORD=1|LibReference=RES|PartCount=2|DisplayModeCount=2|IndexInSheet=106|OwnerPartId=-1|Location.X=1180|Location.Y=580|CurrentPartId=1|SourceLibraryName=Altium Content Vault|TargetFileName=*|AreaColor=11599871|Color=128|PartIDLocked=F|DesignItemId=CMP-2002-08434-1|AllPinCount=2|ComponentKindVersion2=5
|RECORD=2|OwnerIndex=1000|OwnerPartId=1|OwnerPartDisplayMode=1|FormalType=1|Electrical=4|PinConglomerate=32|PinLength=10|Location.X=1200|Location.Y=570|Name=2|Designator=2|PinPropagationDelay=0.000000E+000
|RECORD=2|OwnerIndex=1000|OwnerPartId=1|OwnerPartDisplayMode=1|FormalType=1|Electrical=4|PinConglomerate=34|PinLength=10|Location.X=1180|Location.Y=570|Name=1|Designator=1|PinPropagationDelay=0.000000E+000
|RECORD=14|OwnerIndex=1000|IsNotAccesible=T|IndexInSheet=2|OwnerPartId=1|OwnerPartDisplayMode=1|Location.X=1180|Location.Y=566|Corner.X=1200|Corner.Y=574|LineWidth=1|Color=16711680|AreaColor=11599871
|RECORD=2|OwnerIndex=1000|OwnerPartId=1|FormalType=1|Electrical=4|PinConglomerate=32|PinLength=10|Location.X=1200|Location.Y=570|Name=2|Designator=2|PinPropagationDelay=0.000000E+000
|RECORD=2|OwnerIndex=1000|OwnerPartId=1|FormalType=1|Electrical=4|PinConglomerate=34|PinLength=10|Location.X=1180|Location.Y=570|Name=1|Designator=1|PinPropagationDelay=0.000000E+000
|RECORD=6|OwnerIndex=1000|IsNotAccesible=T|IndexInSheet=5|OwnerPartId=1|LineWidth=1|Color=16711680|LocationCount=10|X1=1200|Y1=570|X2=1196|Y2=570|X3=1195|Y3=568|X4=1193|Y4=572|X5=1191|Y5=568|X6=1189|Y6=572|X7=1187|Y7=568|X8=1185|Y8=572|X9=1184|Y9=570|X10=1180|Y10=570
|RECORD=41|OwnerIndex=1000|IndexInSheet=6|OwnerPartId=-1|Location.X=1168|Location.Y=583|Color=8388608|FontID=1|IsHidden=T|Text=CRCW040227R0FKED|Name=Part Number
|RECORD=41|OwnerIndex=1000|IndexInSheet=7|OwnerPartId=-1|Location.X=1168|Location.Y=583|Color=8388608|FontID=1|IsHidden=T|Text=Vishay Dale|Name=Manufacturer
|RECORD=34|OwnerIndex=1000|IndexInSheet=-1|OwnerPartId=-1|Location.X=1160|Location.Y=570|Color=8388608|FontID=1|Text=R148|Name=Designator|ReadOnlyState=1
|RECORD=41|OwnerIndex=1000|IndexInSheet=-1|OwnerPartId=-1|Location.X=1180|Location.Y=570|Color=8388608|FontID=1|Text=DNI_27_1%_0402|Name=Comment
|RECORD=44|OwnerIndex=1000
|RECORD=45|OwnerIndex=1015|IndexInSheet=-1|Description=Chip Resistor, 2-Leads, Body 1.00x0.50mm, IPC Medium Density|UseComponentLibrary=T|ModelName=RESC1005X40X25NL05T05|ModelType=PCBLIB|DatafileCount=1|ModelDatafileEntity0=RESC1005X40X25NL05T05|ModelDatafileKind0=PCBLib|IsCurrent=T|DatalinksLocked=T|DatabaseDatalinksLocked=T
|RECORD=46|OwnerIndex=1016
|RECORD=48|OwnerIndex=1016
|RECORD=41|OwnerIndex=1018|IndexInSheet=-1|OwnerPartId=-1|Color=8388608|FontID=1|IsHidden=T|Text=2D|Name=Available Preview Images
|RECORD=45|OwnerIndex=1015|IndexInSheet=-1|Description=Chip Resistor, 2-Leads, Body 1.00x0.50mm, IPC High Density|UseComponentLibrary=T|ModelName=RESC1005X40X25LL05T05|ModelType=PCBLIB|DatafileCount=1|ModelDatafileEntity0=RESC1005X40X25LL05T05|ModelDatafileKind0=PCBLib|DatalinksLocked=T|DatabaseDatalinksLocked=T
|RECORD=46|OwnerIndex=1020
|RECORD=48|OwnerIndex=1020
|RECORD=41|OwnerIndex=1022|IndexInSheet=-1|OwnerPartId=-1|Color=8388608|FontID=1|IsHidden=T|Text=2D|Name=Available Preview Images
|RECORD=45|OwnerIndex=1015|IndexInSheet=-1|Description=Chip Resistor, 2-Leads, Body 1.00x0.50mm, IPC Low Density|UseComponentLibrary=T|ModelName=RESC1005X40X25ML05T05|ModelType=PCBLIB|DatafileCount=1|ModelDatafileEntity0=RESC1005X40X25ML05T05|ModelDatafileKind0=PCBLib|DatalinksLocked=T|DatabaseDatalinksLocked=T
|RECORD=46|OwnerIndex=1024
|RECORD=48|OwnerIndex=1024
|RECORD=41|OwnerIndex=1026|IndexInSheet=-1|OwnerPartId=-1|Color=8388608|FontID=1|IsHidden=T|Text=2D|Name=Available Preview Images
|RECORD=1|LibReference=RES|PartCount=2|DisplayModeCount=2|IndexInSheet=107|OwnerPartId=-1|Location.X=1180|Location.Y=570|CurrentPartId=1|SourceLibraryName=Altium Content Vault|TargetFileName=*|AreaColor=11599871|Color=128|PartIDLocked=F|DesignItemId=CMP-2002-08434-1|AllPinCount=2|ComponentKindVersion2=5
|RECORD=2|OwnerIndex=1028|OwnerPartId=1|OwnerPartDisplayMode=1|FormalType=1|Electrical=4|PinConglomerate=32|PinLength=10|Location.X=1200|Location.Y=560|Name=2|Designator=2|PinPropagationDelay=0.000000E+000
|RECORD=2|OwnerIndex=1028|OwnerPartId=1|OwnerPartDisplayMode=1|FormalType=1|Electrical=4|PinConglomerate=34|PinLength=10|Location.X=1180|Location.Y=560|Name=1|Designator=1|PinPropagationDelay=0.000000E+000
|RECORD=14|OwnerIndex=1028|IsNotAccesible=T|IndexInSheet=2|OwnerPartId=1|OwnerPartDisplayMode=1|Location.X=1180|Location.Y=556|Corner.X=1200|Corner.Y=564|LineWidth=1|Color=16711680|AreaColor=11599871
|RECORD=2|OwnerIndex=1028|OwnerPartId=1|FormalType=1|Electrical=4|PinConglomerate=32|PinLength=10|Location.X=1200|Location.Y=560|Name=2|Designator=2|PinPropagationDelay=0.000000E+000
|RECORD=2|OwnerIndex=1028|OwnerPartId=1|FormalType=1|Electrical=4|PinConglomerate=34|PinLength=10|Location.X=1180|Location.Y=560|Name=1|Designator=1|PinPropagationDelay=0.000000E+000
|RECORD=6|OwnerIndex=1028|IsNotAccesible=T|IndexInSheet=5|OwnerPartId=1|LineWidth=1|Color=16711680|LocationCount=10|X1=1200|Y1=560|X2=1196|Y2=560|X3=1195|Y3=558|X4=1193|Y4=562|X5=1191|Y5=558|X6=1189|Y6=562|X7=1187|Y7=558|X8=1185|Y8=562|X9=1184|Y9=560|X10=1180|Y10=560
|RECORD=41|OwnerIndex=1028|IndexInSheet=6|OwnerPartId=-1|Location.X=1168|Location.Y=573|Color=8388608|FontID=1|IsHidden=T|Text=CRCW040227R0FKED|Name=Part Number
|RECORD=41|OwnerIndex=1028|IndexInSheet=7|OwnerPartId=-1|Location.X=1168|Location.Y=573|Color=8388608|FontID=1|IsHidden=T|Text=Vishay Dale|Name=Manufacturer
|RECORD=34|OwnerIndex=1028|IndexInSheet=-1|OwnerPartId=-1|Location.X=1160|Location.Y=560|Color=8388608|FontID=1|Text=R149|Name=Designator|ReadOnlyState=1
|RECORD=41|OwnerIndex=1028|IndexInSheet=-1|OwnerPartId=-1|Location.X=1180|Location.Y=560|Color=8388608|FontID=1|Text=DNI_27_1%_0402|Name=Comment
|RECORD=44|OwnerIndex=1028
|RECORD=45|OwnerIndex=1043|IndexInSheet=-1|Description=Chip Resistor, 2-Leads, Body 1.00x0.50mm, IPC Medium Density|UseComponentLibrary=T|ModelName=RESC1005X40X25NL05T05|ModelType=PCBLIB|DatafileCount=1|ModelDatafileEntity0=RESC1005X40X25NL05T05|ModelDatafileKind0=PCBLib|IsCurrent=T|DatalinksLocked=T|DatabaseDatalinksLocked=T
|RECORD=46|OwnerIndex=1044
|RECORD=48|OwnerIndex=1044
|RECORD=41|OwnerIndex=1046|IndexInSheet=-1|OwnerPartId=-1|Color=8388608|FontID=1|IsHidden=T|Text=2D|Name=Available Preview Images
|RECORD=45|OwnerIndex=1043|IndexInSheet=-1|Description=Chip Resistor, 2-Leads, Body 1.00x0.50mm, IPC High Density|UseComponentLibrary=T|ModelName=RESC1005X40X25LL05T05|ModelType=PCBLIB|DatafileCount=1|ModelDatafileEntity0=RESC1005X40X25LL05T05|ModelDatafileKind0=PCBLib|DatalinksLocked=T|DatabaseDatalinksLocked=T
|RECORD=46|OwnerIndex=1048
|RECORD=48|OwnerIndex=1048
|RECORD=41|OwnerIndex=1050|IndexInSheet=-1|OwnerPartId=-1|Color=8388608|FontID=1|IsHidden=T|Text=2D|Name=Available Preview Images
|RECORD=45|OwnerIndex=1043|IndexInSheet=-1|Description=Chip Resistor, 2-Leads, Body 1.00x0.50mm, IPC Low Density|UseComponentLibrary=T|ModelName=RESC1005X40X25ML05T05|ModelType=PCBLIB|DatafileCount=1|ModelDatafileEntity0=RESC1005X40X25ML05T05|ModelDatafileKind0=PCBLib|DatalinksLocked=T|DatabaseDatalinksLocked=T
|RECORD=46|OwnerIndex=1052
|RECORD=48|OwnerIndex=1052
|RECORD=41|OwnerIndex=1054|IndexInSheet=-1|OwnerPartId=-1|Color=8388608|FontID=1|IsHidden=T|Text=2D|Name=Available Preview Images
|RECORD=1|LibReference=RES|PartCount=2|DisplayModeCount=2|IndexInSheet=108|OwnerPartId=-1|Location.X=1180|Location.Y=550|CurrentPartId=1|SourceLibraryName=Altium Content Vault|TargetFileName=*|AreaColor=11599871|Color=128|PartIDLocked=F|DesignItemId=CMP-2002-08434-1|AllPinCount=2|ComponentKindVersion2=5
|RECORD=2|OwnerIndex=1056|OwnerPartId=1|OwnerPartDisplayMode=1|FormalType=1|Electrical=4|PinConglomerate=32|PinLength=10|Location.X=1200|Location.Y=540|Name=2|Designator=2|PinPropagationDelay=0.000000E+000
|RECORD=2|OwnerIndex=1056|OwnerPartId=1|OwnerPartDisplayMode=1|FormalType=1|Electrical=4|PinConglomerate=34|PinLength=10|Location.X=1180|Location.Y=540|Name=1|Designator=1|PinPropagationDelay=0.000000E+000
|RECORD=14|OwnerIndex=1056|IsNotAccesible=T|IndexInSheet=2|OwnerPartId=1|OwnerPartDisplayMode=1|Location.X=1180|Location.Y=536|Corner.X=1200|Corner.Y=544|LineWidth=1|Color=16711680|AreaColor=11599871
|RECORD=2|OwnerIndex=1056|OwnerPartId=1|FormalType=1|Electrical=4|PinConglomerate=32|PinLength=10|Location.X=1200|Location.Y=540|Name=2|Designator=2|PinPropagationDelay=0.000000E+000
|RECORD=2|OwnerIndex=1056|OwnerPartId=1|FormalType=1|Electrical=4|PinConglomerate=34|PinLength=10|Location.X=1180|Location.Y=540|Name=1|Designator=1|PinPropagationDelay=0.000000E+000
|RECORD=6|OwnerIndex=1056|IsNotAccesible=T|IndexInSheet=5|OwnerPartId=1|LineWidth=1|Color=16711680|LocationCount=10|X1=1200|Y1=540|X2=1196|Y2=540|X3=1195|Y3=538|X4=1193|Y4=542|X5=1191|Y5=538|X6=1189|Y6=542|X7=1187|Y7=538|X8=1185|Y8=542|X9=1184|Y9=540|X10=1180|Y10=540
|RECORD=41|OwnerIndex=1056|IndexInSheet=6|OwnerPartId=-1|Location.X=1168|Location.Y=553|Color=8388608|FontID=1|IsHidden=T|Text=CRCW040227R0FKED|Name=Part Number
|RECORD=41|OwnerIndex=1056|IndexInSheet=7|OwnerPartId=-1|Location.X=1168|Location.Y=553|Color=8388608|FontID=1|IsHidden=T|Text=Vishay Dale|Name=Manufacturer
|RECORD=34|OwnerIndex=1056|IndexInSheet=-1|OwnerPartId=-1|Location.X=1160|Location.Y=540|Color=8388608|FontID=1|Text=R153|Name=Designator|ReadOnlyState=1
|RECORD=41|OwnerIndex=1056|IndexInSheet=-1|OwnerPartId=-1|Location.X=1180|Location.Y=540|Color=8388608|FontID=1|Text=DNI_27_1%_0402|Name=Comment
|RECORD=44|OwnerIndex=1056
|RECORD=45|OwnerIndex=1071|IndexInSheet=-1|Description=Chip Resistor, 2-Leads, Body 1.00x0.50mm, IPC Medium Density|UseComponentLibrary=T|ModelName=RESC1005X40X25NL05T05|ModelType=PCBLIB|DatafileCount=1|ModelDatafileEntity0=RESC1005X40X25NL05T05|ModelDatafileKind0=PCBLib|IsCurrent=T|DatalinksLocked=T|DatabaseDatalinksLocked=T
|RECORD=46|OwnerIndex=1072
|RECORD=48|OwnerIndex=1072
|RECORD=41|OwnerIndex=1074|IndexInSheet=-1|OwnerPartId=-1|Color=8388608|FontID=1|IsHidden=T|Text=2D|Name=Available Preview Images
|RECORD=45|OwnerIndex=1071|IndexInSheet=-1|Description=Chip Resistor, 2-Leads, Body 1.00x0.50mm, IPC High Density|UseComponentLibrary=T|ModelName=RESC1005X40X25LL05T05|ModelType=PCBLIB|DatafileCount=1|ModelDatafileEntity0=RESC1005X40X25LL05T05|ModelDatafileKind0=PCBLib|DatalinksLocked=T|DatabaseDatalinksLocked=T
|RECORD=46|OwnerIndex=1076
|RECORD=48|OwnerIndex=1076
|RECORD=41|OwnerIndex=1078|IndexInSheet=-1|OwnerPartId=-1|Color=8388608|FontID=1|IsHidden=T|Text=2D|Name=Available Preview Images
|RECORD=45|OwnerIndex=1071|IndexInSheet=-1|Description=Chip Resistor, 2-Leads, Body 1.00x0.50mm, IPC Low Density|UseComponentLibrary=T|ModelName=RESC1005X40X25ML05T05|ModelType=PCBLIB|DatafileCount=1|ModelDatafileEntity0=RESC1005X40X25ML05T05|ModelDatafileKind0=PCBLib|DatalinksLocked=T|DatabaseDatalinksLocked=T
|RECORD=46|OwnerIndex=1080
|RECORD=48|OwnerIndex=1080
|RECORD=41|OwnerIndex=1082|IndexInSheet=-1|OwnerPartId=-1|Color=8388608|FontID=1|IsHidden=T|Text=2D|Name=Available Preview Images
|RECORD=1|LibReference=RES|PartCount=2|DisplayModeCount=2|IndexInSheet=109|OwnerPartId=-1|Location.X=1180|Location.Y=560|CurrentPartId=1|SourceLibraryName=Altium Content Vault|TargetFileName=*|AreaColor=11599871|Color=128|PartIDLocked=F|DesignItemId=CMP-2002-08434-1|AllPinCount=2|ComponentKindVersion2=5
|RECORD=2|OwnerIndex=1084|OwnerPartId=1|OwnerPartDisplayMode=1|FormalType=1|Electrical=4|PinConglomerate=32|PinLength=10|Location.X=1200|Location.Y=550|Name=2|Designator=2|PinPropagationDelay=0.000000E+000
|RECORD=2|OwnerIndex=1084|OwnerPartId=1|OwnerPartDisplayMode=1|FormalType=1|Electrical=4|PinConglomerate=34|PinLength=10|Location.X=1180|Location.Y=550|Name=1|Designator=1|PinPropagationDelay=0.000000E+000
|RECORD=14|OwnerIndex=1084|IsNotAccesible=T|IndexInSheet=2|OwnerPartId=1|OwnerPartDisplayMode=1|Location.X=1180|Location.Y=546|Corner.X=1200|Corner.Y=554|LineWidth=1|Color=16711680|AreaColor=11599871
|RECORD=2|OwnerIndex=1084|OwnerPartId=1|FormalType=1|Electrical=4|PinConglomerate=32|PinLength=10|Location.X=1200|Location.Y=550|Name=2|Designator=2|PinPropagationDelay=0.000000E+000
|RECORD=2|OwnerIndex=1084|OwnerPartId=1|FormalType=1|Electrical=4|PinConglomerate=34|PinLength=10|Location.X=1180|Location.Y=550|Name=1|Designator=1|PinPropagationDelay=0.000000E+000
|RECORD=6|OwnerIndex=1084|IsNotAccesible=T|IndexInSheet=5|OwnerPartId=1|LineWidth=1|Color=16711680|LocationCount=10|X1=1200|Y1=550|X2=1196|Y2=550|X3=1195|Y3=548|X4=1193|Y4=552|X5=1191|Y5=548|X6=1189|Y6=552|X7=1187|Y7=548|X8=1185|Y8=552|X9=1184|Y9=550|X10=1180|Y10=550
|RECORD=41|OwnerIndex=1084|IndexInSheet=6|OwnerPartId=-1|Location.X=1168|Location.Y=563|Color=8388608|FontID=1|IsHidden=T|Text=CRCW040227R0FKED|Name=Part Number
|RECORD=41|OwnerIndex=1084|IndexInSheet=7|OwnerPartId=-1|Location.X=1168|Location.Y=563|Color=8388608|FontID=1|IsHidden=T|Text=Vishay Dale|Name=Manufacturer
|RECORD=34|OwnerIndex=1084|IndexInSheet=-1|OwnerPartId=-1|Location.X=1160|Location.Y=550|Color=8388608|FontID=1|Text=R151|Name=Designator|ReadOnlyState=1
|RECORD=41|OwnerIndex=1084|IndexInSheet=-1|OwnerPartId=-1|Location.X=1180|Location.Y=550|Color=8388608|FontID=1|Text=DNI_27_1%_0402|Name=Comment
|RECORD=44|OwnerIndex=1084
|RECORD=45|OwnerIndex=1099|IndexInSheet=-1|Description=Chip Resistor, 2-Leads, Body 1.00x0.50mm, IPC Medium Density|UseComponentLibrary=T|ModelName=RESC1005X40X25NL05T05|ModelType=PCBLIB|DatafileCount=1|ModelDatafileEntity0=RESC1005X40X25NL05T05|ModelDatafileKind0=PCBLib|IsCurrent=T|DatalinksLocked=T|DatabaseDatalinksLocked=T
|RECORD=46|OwnerIndex=1100
|RECORD=48|OwnerIndex=1100
|RECORD=41|OwnerIndex=1102|IndexInSheet=-1|OwnerPartId=-1|Color=8388608|FontID=1|IsHidden=T|Text=2D|Name=Available Preview Images
|RECORD=45|OwnerIndex=1099|IndexInSheet=-1|Description=Chip Resistor, 2-Leads, Body 1.00x0.50mm, IPC High Density|UseComponentLibrary=T|ModelName=RESC1005X40X25LL05T05|ModelType=PCBLIB|DatafileCount=1|ModelDatafileEntity0=RESC1005X40X25LL05T05|ModelDatafileKind0=PCBLib|DatalinksLocked=T|DatabaseDatalinksLocked=T
|RECORD=46|OwnerIndex=1104
|RECORD=48|OwnerIndex=1104
|RECORD=41|OwnerIndex=1106|IndexInSheet=-1|OwnerPartId=-1|Color=8388608|FontID=1|IsHidden=T|Text=2D|Name=Available Preview Images
|RECORD=45|OwnerIndex=1099|IndexInSheet=-1|Description=Chip Resistor, 2-Leads, Body 1.00x0.50mm, IPC Low Density|UseComponentLibrary=T|ModelName=RESC1005X40X25ML05T05|ModelType=PCBLIB|DatafileCount=1|ModelDatafileEntity0=RESC1005X40X25ML05T05|ModelDatafileKind0=PCBLib|DatalinksLocked=T|DatabaseDatalinksLocked=T
|RECORD=46|OwnerIndex=1108
|RECORD=48|OwnerIndex=1108
|RECORD=41|OwnerIndex=1110|IndexInSheet=-1|OwnerPartId=-1|Color=8388608|FontID=1|IsHidden=T|Text=2D|Name=Available Preview Images
|RECORD=1|LibReference=12a319ab100cd6cfe745e35972674f5|ComponentDescription=IC SWITCH SPDT DUAL 12UQFN|PartCount=2|DisplayModeCount=1|IndexInSheet=110|OwnerPartId=-1|Location.X=950|Location.Y=360|CurrentPartId=1|LibraryPath=*|SourceLibraryName=Altium Content Vault|TargetFileName=*|AreaColor=11599871|Color=128|PartIDLocked=T|DesignItemId=CMP-04892-000114-1|AllPinCount=12
|RECORD=14|OwnerIndex=1112|IsNotAccesible=T|OwnerPartId=1|Location.X=970|Location.Y=200|Corner.X=1070|Corner.Y=370|LineWidth=1|Color=128|AreaColor=11599871|IsSolid=T
|RECORD=2|OwnerIndex=1112|OwnerPartId=1|Electrical=7|PinConglomerate=58|PinLength=20|Location.X=970|Location.Y=360|Name=VCC|Designator=9|PinName_PositionConglomerate=16|Name_CustomFontID=1|PinDesignator_PositionConglomerate=16|Designator_CustomFontID=1|PinPropagationDelay=0.000000E+000
|RECORD=2|OwnerIndex=1112|OwnerPartId=1|PinConglomerate=58|PinLength=20|Location.X=970|Location.Y=260|Name=SEL1|Designator=1|PinName_PositionConglomerate=16|Name_CustomFontID=1|PinDesignator_PositionConglomerate=16|Designator_CustomFontID=1|PinPropagationDelay=0.000000E+000
|RECORD=2|OwnerIndex=1112|OwnerPartId=1|PinConglomerate=58|PinLength=20|Location.X=970|Location.Y=250|Name=SEL2|Designator=5|PinName_PositionConglomerate=16|Name_CustomFontID=1|PinDesignator_PositionConglomerate=16|Designator_CustomFontID=1|PinPropagationDelay=0.000000E+000
|RECORD=2|OwnerIndex=1112|OwnerPartId=1|Electrical=4|PinConglomerate=58|PinLength=20|Location.X=970|Location.Y=320|Name=NO1|Designator=2|PinName_PositionConglomerate=16|Name_CustomFontID=1|PinDesignator_PositionConglomerate=16|Designator_CustomFontID=1|PinPropagationDelay=0.000000E+000
|RECORD=2|OwnerIndex=1112|OwnerPartId=1|Electrical=4|PinConglomerate=58|PinLength=20|Location.X=970|Location.Y=280|Name=NO2|Designator=4|PinName_PositionConglomerate=16|Name_CustomFontID=1|PinDesignator_PositionConglomerate=16|Designator_CustomFontID=1|PinPropagationDelay=0.000000E+000
|RECORD=2|OwnerIndex=1112|OwnerPartId=1|Electrical=4|PinConglomerate=56|PinLength=20|Location.X=1070|Location.Y=340|Name=COM1|Designator=11|PinName_PositionConglomerate=16|Name_CustomFontID=1|PinDesignator_PositionConglomerate=16|Designator_CustomFontID=1|PinPropagationDelay=0.000000E+000
|RECORD=2|OwnerIndex=1112|OwnerPartId=1|Electrical=4|PinConglomerate=56|PinLength=20|Location.X=1070|Location.Y=300|Name=COM2|Designator=7|PinName_PositionConglomerate=16|Name_CustomFontID=1|PinDesignator_PositionConglomerate=16|Designator_CustomFontID=1|PinPropagationDelay=0.000000E+000
|RECORD=2|OwnerIndex=1112|OwnerPartId=1|Electrical=3|PinConglomerate=58|PinLength=20|Location.X=970|Location.Y=210|Name=F\L\T\|Designator=12|PinName_PositionConglomerate=16|Name_CustomFontID=1|PinDesignator_PositionConglomerate=16|Designator_CustomFontID=1|PinPropagationDelay=0.000000E+000
|RECORD=2|OwnerIndex=1112|OwnerPartId=1|PinConglomerate=58|PinLength=20|Location.X=970|Location.Y=230|Name=O\E\|Designator=6|PinName_PositionConglomerate=16|Name_CustomFontID=1|PinDesignator_PositionConglomerate=16|Designator_CustomFontID=1|PinPropagationDelay=0.000000E+000
|RECORD=2|OwnerIndex=1112|OwnerPartId=1|Electrical=4|PinConglomerate=58|PinLength=20|Location.X=970|Location.Y=340|Name=NC1|Designator=10|PinName_PositionConglomerate=16|Name_CustomFontID=1|PinDesignator_PositionConglomerate=16|Designator_CustomFontID=1|PinPropagationDelay=0.000000E+000
|RECORD=2|OwnerIndex=1112|OwnerPartId=1|Electrical=4|PinConglomerate=58|PinLength=20|Location.X=970|Location.Y=300|Name=NC2|Designator=8|PinName_PositionConglomerate=16|Name_CustomFontID=1|PinDesignator_PositionConglomerate=16|Designator_CustomFontID=1|PinPropagationDelay=0.000000E+000
|RECORD=2|OwnerIndex=1112|OwnerPartId=1|Electrical=7|PinConglomerate=56|PinLength=20|Location.X=1070|Location.Y=210|Name=GND|Designator=3|PinName_PositionConglomerate=16|Name_CustomFontID=1|PinDesignator_PositionConglomerate=16|Designator_CustomFontID=1|PinPropagationDelay=0.000000E+000
|RECORD=41|OwnerIndex=1112|IndexInSheet=13|OwnerPartId=-1|Location.X=948|Location.Y=370|Color=8388608|FontID=1|IsHidden=T|Text=12|Name=Number of Pins
|RECORD=41|OwnerIndex=1112|IndexInSheet=14|OwnerPartId=-1|Location.X=948|Location.Y=370|Color=8388608|FontID=1|IsHidden=T|Text=2|Name=Number of Circuits
|RECORD=41|OwnerIndex=1112|IndexInSheet=15|OwnerPartId=-1|Location.X=948|Location.Y=370|Color=8388608|FontID=1|IsHidden=T|Text=-40°C|Name=Min Operating Temperature
|RECORD=41|OwnerIndex=1112|IndexInSheet=16|OwnerPartId=-1|Location.X=948|Location.Y=370|Color=8388608|FontID=1|IsHidden=T|Text=Yes|Name=RoHS Compliant
|RECORD=41|OwnerIndex=1112|IndexInSheet=17|OwnerPartId=-1|Location.X=948|Location.Y=370|Color=8388608|FontID=1|IsHidden=T|Text=1.2GHz|Name=-3db Bandwidth
|RECORD=41|OwnerIndex=1112|IndexInSheet=18|OwnerPartId=-1|Location.X=948|Location.Y=370|Color=8388608|FontID=1|IsHidden=T|Text=125°C|Name=Max Operating Temperature
|RECORD=41|OwnerIndex=1112|IndexInSheet=19|OwnerPartId=-1|Location.X=948|Location.Y=370|Color=8388608|FontID=1|IsHidden=T|Text=2|Name=Number of Channels
|RECORD=41|OwnerIndex=1112|IndexInSheet=20|OwnerPartId=-1|Location.X=948|Location.Y=370|Color=8388608|FontID=1|IsHidden=T|Text=18R|Name=On-State Resistance
|RECORD=41|OwnerIndex=1112|IndexInSheet=21|OwnerPartId=-1|Location.X=948|Location.Y=370|Color=8388608|FontID=1|IsHidden=T|Text=Tape and Reel|Name=Packaging
|RECORD=34|OwnerIndex=1112|IndexInSheet=-1|OwnerPartId=-1|Location.X=970|Location.Y=370|Color=8388608|FontID=1|Text=U30|Name=Designator|ReadOnlyState=1
|RECORD=41|OwnerIndex=1112|IndexInSheet=-1|OwnerPartId=1|Location.X=970|Location.Y=190|Color=8388608|FontID=1|Text=TMUX1072RUTR|Name=Comment
|RECORD=44|OwnerIndex=1112
|RECORD=45|OwnerIndex=1149|IndexInSheet=-1|UseComponentLibrary=T|ModelName=FP-RUT0012A-MFG|ModelType=PCBLIB|DatafileCount=1|ModelDatafileEntity0=FP-RUT0012A-MFG|ModelDatafileKind0=PCBLib|IsCurrent=T|DatalinksLocked=T|DatabaseDatalinksLocked=T
|RECORD=46|OwnerIndex=1150
|RECORD=48|OwnerIndex=1150
|RECORD=17|IndexInSheet=111|OwnerPartId=-1|Style=4|ShowNetName=T|Location.X=930|Location.Y=200|Orientation=3|Color=128|FontID=1|Text=GND
|RECORD=1|LibReference=b4654b650e69147ec39a6b967a45e02|ComponentDescription=General Purpose Ceramic Capacitor, 0402, 100nF, 10%, X7R, 15%, 25V|PartCount=2|DisplayModeCount=1|IndexInSheet=112|OwnerPartId=-1|Location.X=890|Location.Y=390|CurrentPartId=1|LibraryPath=*|SourceLibraryName=Altium Content Vault|TargetFileName=*|AreaColor=11599871|Color=128|PartIDLocked=T|DesignItemId=CMP-2008-02519-2|AllPinCount=2
|RECORD=2|OwnerIndex=1154|OwnerPartId=1|Electrical=4|PinConglomerate=49|PinLength=7|Location.X=890|Location.Y=383|Name=1|Designator=1|PinPropagationDelay=0.000000E+000
|RECORD=2|OwnerIndex=1154|OwnerPartId=1|Electrical=4|PinConglomerate=51|PinLength=6|Location.X=890|Location.Y=376|Name=2|Designator=2|PinPropagationDelay=0.000000E+000
|RECORD=13|OwnerIndex=1154|IsNotAccesible=T|IndexInSheet=2|OwnerPartId=1|Location.X=900|Location.Y=383|Corner.X=880|Corner.Y=383|LineWidth=1|Color=16711680
|RECORD=13|OwnerIndex=1154|IsNotAccesible=T|IndexInSheet=3|OwnerPartId=1|Location.X=900|Location.Y=377|Corner.X=880|Corner.Y=377|LineWidth=1|Color=16711680
|RECORD=13|OwnerIndex=1154|IsNotAccesible=T|IndexInSheet=4|OwnerPartId=1|Location.X=890|Location.Y=383|Corner.X=890|Corner.Y=386|LineWidth=1|Color=16711680
|RECORD=13|OwnerIndex=1154|IsNotAccesible=T|IndexInSheet=5|OwnerPartId=1|Location.X=890|Location.Y=376|Corner.X=890|Corner.Y=375|LineWidth=1|Color=16711680
|RECORD=41|OwnerIndex=1154|IndexInSheet=6|OwnerPartId=-1|Location.X=879|Location.Y=392|Color=8388608|FontID=1|IsHidden=T|Text=1|Name=Package Quantity
|RECORD=41|OwnerIndex=1154|IndexInSheet=7|OwnerPartId=-1|Location.X=879|Location.Y=392|Color=8388608|FontID=1|IsHidden=T|Text=100nF|Name=Capacitance
|RECORD=41|OwnerIndex=1154|IndexInSheet=8|OwnerPartId=-1|Location.X=879|Location.Y=392|Color=8388608|FontID=1|IsHidden=T|Text=-55°C|Name=Min Operating Temperature
|RECORD=41|OwnerIndex=1154|IndexInSheet=9|OwnerPartId=-1|Location.X=879|Location.Y=392|Color=8388608|FontID=1|IsHidden=T|Text=25V|Name=Voltage
|RECORD=41|OwnerIndex=1154|IndexInSheet=10|OwnerPartId=-1|Location.X=879|Location.Y=392|Color=8388608|FontID=1|IsHidden=T|Text=25V|Name=Voltage Rating
|RECORD=41|OwnerIndex=1154|IndexInSheet=11|OwnerPartId=-1|Location.X=879|Location.Y=392|Color=8388608|FontID=1|IsHidden=T|Text=Flat|Name=Construction
|RECORD=41|OwnerIndex=1154|IndexInSheet=12|OwnerPartId=-1|Location.X=879|Location.Y=392|Color=8388608|FontID=1|IsHidden=T|Text=125°C|Name=Max Operating Temperature
|RECORD=41|OwnerIndex=1154|IndexInSheet=13|OwnerPartId=-1|Location.X=879|Location.Y=392|Color=8388608|FontID=1|IsHidden=T|Text=No|Name=Radiation Hardening
|RECORD=41|OwnerIndex=1154|IndexInSheet=14|OwnerPartId=-1|Location.X=879|Location.Y=392|Color=8388608|FontID=1|IsHidden=T|Text=0.5mm|Name=Depth
|RECORD=41|OwnerIndex=1154|IndexInSheet=15|OwnerPartId=-1|Location.X=879|Location.Y=392|Color=8388608|FontID=1|IsHidden=T|Text=0.022inch|Name=Thickness
|RECORD=41|OwnerIndex=1154|IndexInSheet=16|OwnerPartId=-1|Location.X=879|Location.Y=392|Color=8388608|FontID=1|IsHidden=T|Text=25V|Name=Voltage Rating (DC)
|RECORD=41|OwnerIndex=1154|IndexInSheet=17|OwnerPartId=-1|Location.X=879|Location.Y=392|Color=8388608|FontID=1|IsHidden=T|Text=2|Name=Number of Pins
|RECORD=41|OwnerIndex=1154|IndexInSheet=18|OwnerPartId=-1|Location.X=879|Location.Y=392|Color=8388608|FontID=1|IsHidden=T|Text=Lead Free|Name=Lead Free
|RECORD=41|OwnerIndex=1154|IndexInSheet=19|OwnerPartId=-1|Location.X=879|Location.Y=392|Color=8388608|FontID=1|IsHidden=T|Text=-|Name=Series
|RECORD=41|OwnerIndex=1154|IndexInSheet=20|OwnerPartId=-1|Location.X=879|Location.Y=392|Color=8388608|FontID=1|IsHidden=T|Text=No SVHC|Name=REACH SVHC
|RECORD=41|OwnerIndex=1154|IndexInSheet=21|OwnerPartId=-1|Location.X=879|Location.Y=392|Color=8388608|FontID=1|IsHidden=T|Text=1mm|Name=Length
|RECORD=41|OwnerIndex=1154|IndexInSheet=22|OwnerPartId=-1|Location.X=879|Location.Y=392|Color=8388608|FontID=1|IsHidden=T|Text=X7R|Name=Dielectric
|RECORD=41|OwnerIndex=1154|IndexInSheet=23|OwnerPartId=-1|Location.X=879|Location.Y=392|Color=8388608|FontID=1|IsHidden=T|Text=Yes|Name=RoHS Compliant
|RECORD=41|OwnerIndex=1154|IndexInSheet=24|OwnerPartId=-1|Location.X=879|Location.Y=392|Color=8388608|FontID=1|IsHidden=T|Text=Surface Mount|Name=Mount
|RECORD=41|OwnerIndex=1154|IndexInSheet=25|OwnerPartId=-1|Location.X=879|Location.Y=392|Color=8388608|FontID=1|IsHidden=T|Text=Tape and Reel|Name=Packaging
|RECORD=41|OwnerIndex=1154|IndexInSheet=26|OwnerPartId=-1|Location.X=879|Location.Y=392|Color=8388608|FontID=1|IsHidden=T|Text=0402|Name=Case/Package
|RECORD=41|OwnerIndex=1154|IndexInSheet=27|OwnerPartId=-1|Location.X=879|Location.Y=392|Color=8388608|FontID=1|IsHidden=T|Text=0402|Name=Case Code (Imperial)
|RECORD=41|OwnerIndex=1154|IndexInSheet=28|OwnerPartId=-1|Location.X=879|Location.Y=392|Color=8388608|FontID=1|IsHidden=T|Text=SMD/SMT|Name=Termination
|RECORD=41|OwnerIndex=1154|IndexInSheet=29|OwnerPartId=-1|Location.X=879|Location.Y=392|Color=8388608|FontID=1|IsHidden=T|Text=0.02inch|Name=Width
|RECORD=41|OwnerIndex=1154|IndexInSheet=30|OwnerPartId=-1|Location.X=879|Location.Y=392|Color=8388608|FontID=1|IsHidden=T|Text=1005|Name=Case Code (Metric)
|RECORD=41|OwnerIndex=1154|IndexInSheet=31|OwnerPartId=-1|Location.X=879|Location.Y=392|Color=8388608|FontID=1|IsHidden=T|Text=10%|Name=Tolerance
|RECORD=34|OwnerIndex=1154|IndexInSheet=-1|OwnerPartId=-1|Location.X=880|Location.Y=370|Orientation=1|Color=8388608|FontID=2|Text=C108|Name=Designator|ReadOnlyState=1
|RECORD=41|OwnerIndex=1154|IndexInSheet=-1|OwnerPartId=1|Location.X=910|Location.Y=355|Orientation=1|Color=8388608|FontID=2|Text=0.1uF_25V_0402|Name=Comment
|RECORD=44|OwnerIndex=1154
|RECORD=45|OwnerIndex=1191|IndexInSheet=-1|UseComponentLibrary=T|ModelName=FP-0402-L_1_0_1-W_0_5_0_1-IPC_C|ModelType=PCBLIB|DatafileCount=1|ModelDatafileEntity0=FP-0402-L_1_0_1-W_0_5_0_1-IPC_C|ModelDatafileKind0=PCBLib|IsCurrent=T|DatalinksLocked=T|DatabaseDatalinksLocked=T
|RECORD=46|OwnerIndex=1192
|RECORD=48|OwnerIndex=1192
|RECORD=45|OwnerIndex=1191|IndexInSheet=-1|UseComponentLibrary=T|ModelName=FP-0402-L_1_0_1-W_0_5_0_1-IPC_B|ModelType=PCBLIB|DatafileCount=1|ModelDatafileEntity0=FP-0402-L_1_0_1-W_0_5_0_1-IPC_B|ModelDatafileKind0=PCBLib|DatalinksLocked=T|DatabaseDatalinksLocked=T
|RECORD=46|OwnerIndex=1195
|RECORD=48|OwnerIndex=1195
|RECORD=45|OwnerIndex=1191|IndexInSheet=-1|UseComponentLibrary=T|ModelName=FP-0402-L_1_0_1-W_0_5_0_1-MFG|ModelType=PCBLIB|DatafileCount=1|ModelDatafileEntity0=FP-0402-L_1_0_1-W_0_5_0_1-MFG|ModelDatafileKind0=PCBLib|DatalinksLocked=T|DatabaseDatalinksLocked=T
|RECORD=46|OwnerIndex=1198
|RECORD=48|OwnerIndex=1198
|RECORD=45|OwnerIndex=1191|IndexInSheet=-1|UseComponentLibrary=T|ModelName=FP-0402-L_1_0_1-W_0_5_0_1-IPC_A|ModelType=PCBLIB|DatafileCount=1|ModelDatafileEntity0=FP-0402-L_1_0_1-W_0_5_0_1-IPC_A|ModelDatafileKind0=PCBLib|DatalinksLocked=T|DatabaseDatalinksLocked=T
|RECORD=46|OwnerIndex=1201
|RECORD=48|OwnerIndex=1201
|RECORD=17|IndexInSheet=113|OwnerPartId=-1|ShowNetName=T|Location.X=890|Location.Y=440|Orientation=1|Color=128|FontID=1|Text=+3.3V
|RECORD=17|IndexInSheet=114|OwnerPartId=-1|Style=4|ShowNetName=T|Location.X=890|Location.Y=360|Orientation=3|Color=128|FontID=1|Text=GND
|RECORD=17|IndexInSheet=115|OwnerPartId=-1|ShowNetName=T|Location.X=860|Location.Y=260|Orientation=2|Color=255|FontID=1|Text=DIP_SW_GPS2_SEL|IsCrossSheetConnector=T
|RECORD=17|IndexInSheet=116|OwnerPartId=-1|Style=4|ShowNetName=T|Location.X=1100|Location.Y=200|Orientation=3|Color=128|FontID=1|Text=GND
|RECORD=1|LibReference=RES|PartCount=2|DisplayModeCount=2|IndexInSheet=117|OwnerPartId=-1|Location.X=1250|Location.Y=390|CurrentPartId=1|SourceLibraryName=Altium Content Vault|TargetFileName=*|AreaColor=11599871|Color=128|PartIDLocked=F|DesignItemId=CMP-2002-07709-1|AllPinCount=2|ComponentKindVersion2=5
|RECORD=2|OwnerIndex=1208|OwnerPartId=1|OwnerPartDisplayMode=1|FormalType=1|Electrical=4|PinConglomerate=32|PinLength=10|Location.X=1270|Location.Y=380|Name=2|Designator=2|PinPropagationDelay=0.000000E+000
|RECORD=2|OwnerIndex=1208|OwnerPartId=1|OwnerPartDisplayMode=1|FormalType=1|Electrical=4|PinConglomerate=34|PinLength=10|Location.X=1250|Location.Y=380|Name=1|Designator=1|PinPropagationDelay=0.000000E+000
|RECORD=14|OwnerIndex=1208|IsNotAccesible=T|IndexInSheet=2|OwnerPartId=1|OwnerPartDisplayMode=1|Location.X=1250|Location.Y=376|Corner.X=1270|Corner.Y=384|LineWidth=1|Color=16711680|AreaColor=11599871
|RECORD=2|OwnerIndex=1208|OwnerPartId=1|FormalType=1|Electrical=4|PinConglomerate=32|PinLength=10|Location.X=1270|Location.Y=380|Name=2|Designator=2|PinPropagationDelay=0.000000E+000
|RECORD=2|OwnerIndex=1208|OwnerPartId=1|FormalType=1|Electrical=4|PinConglomerate=34|PinLength=10|Location.X=1250|Location.Y=380|Name=1|Designator=1|PinPropagationDelay=0.000000E+000
|RECORD=6|OwnerIndex=1208|IsNotAccesible=T|IndexInSheet=5|OwnerPartId=1|LineWidth=1|Color=16711680|LocationCount=10|X1=1270|Y1=380|X2=1266|Y2=380|X3=1265|Y3=378|X4=1263|Y4=382|X5=1261|Y5=378|X6=1259|Y6=382|X7=1257|Y7=378|X8=1255|Y8=382|X9=1254|Y9=380|X10=1250|Y10=380
|RECORD=41|OwnerIndex=1208|IndexInSheet=6|OwnerPartId=-1|Location.X=1238|Location.Y=393|Color=8388608|FontID=1|IsHidden=T|Text=Yageo / Phycomp|Name=Manufacturer
|RECORD=41|OwnerIndex=1208|IndexInSheet=7|OwnerPartId=-1|Location.X=1238|Location.Y=393|Color=8388608|FontID=1|IsHidden=T|Text=RC0402FR-0749R9L|Name=Part Number
|RECORD=34|OwnerIndex=1208|IndexInSheet=-1|OwnerPartId=-1|Location.X=1230|Location.Y=380|Color=8388608|FontID=1|Text=R169|Name=Designator|ReadOnlyState=1
|RECORD=41|OwnerIndex=1208|IndexInSheet=-1|OwnerPartId=-1|Location.X=1270|Location.Y=380|Color=8388608|FontID=1|Text=DNI_49.9_1%_0402|Name=Comment
|RECORD=44|OwnerIndex=1208
|RECORD=45|OwnerIndex=1223|IndexInSheet=-1|Description=Chip Resistor, 2-Leads, Body 1.00x0.50mm, IPC High Density|UseComponentLibrary=T|ModelName=RESC1005X40X25LL05T10|ModelType=PCBLIB|DatafileCount=1|ModelDatafileEntity0=RESC1005X40X25LL05T10|ModelDatafileKind0=PCBLib|IsCurrent=T|DatalinksLocked=T|DatabaseDatalinksLocked=T
|RECORD=46|OwnerIndex=1224
|RECORD=48|OwnerIndex=1224
|RECORD=41|OwnerIndex=1226|IndexInSheet=-1|OwnerPartId=-1|Color=8388608|FontID=1|IsHidden=T|Text=2D|Name=Available Preview Images
|RECORD=45|OwnerIndex=1223|IndexInSheet=-1|Description=Chip Resistor, 2-Leads, Body 1.00x0.50mm, IPC Low Density|UseComponentLibrary=T|ModelName=RESC1005X40X25ML05T10|ModelType=PCBLIB|DatafileCount=1|ModelDatafileEntity0=RESC1005X40X25ML05T10|ModelDatafileKind0=PCBLib|DatalinksLocked=T|DatabaseDatalinksLocked=T
|RECORD=46|OwnerIndex=1228
|RECORD=48|OwnerIndex=1228
|RECORD=41|OwnerIndex=1230|IndexInSheet=-1|OwnerPartId=-1|Color=8388608|FontID=1|IsHidden=T|Text=2D|Name=Available Preview Images
|RECORD=45|OwnerIndex=1223|IndexInSheet=-1|Description=Chip Resistor, 2-Leads, Body 1.00x0.50mm, IPC Medium Density|UseComponentLibrary=T|ModelName=RESC1005X40X25NL05T10|ModelType=PCBLIB|DatafileCount=1|ModelDatafileEntity0=RESC1005X40X25NL05T10|ModelDatafileKind0=PCBLib|DatalinksLocked=T|DatabaseDatalinksLocked=T
|RECORD=46|OwnerIndex=1232
|RECORD=48|OwnerIndex=1232
|RECORD=41|OwnerIndex=1234|IndexInSheet=-1|OwnerPartId=-1|Color=8388608|FontID=1|IsHidden=T|Text=2D|Name=Available Preview Images
|RECORD=1|LibReference=RES|PartCount=2|DisplayModeCount=2|IndexInSheet=118|OwnerPartId=-1|Location.X=1250|Location.Y=410|CurrentPartId=1|SourceLibraryName=Altium Content Vault|TargetFileName=*|AreaColor=11599871|Color=128|PartIDLocked=F|DesignItemId=CMP-2002-07709-1|AllPinCount=2|ComponentKindVersion2=5
|RECORD=2|OwnerIndex=1236|OwnerPartId=1|OwnerPartDisplayMode=1|FormalType=1|Electrical=4|PinConglomerate=32|PinLength=10|Location.X=1270|Location.Y=400|Name=2|Designator=2|PinPropagationDelay=0.000000E+000
|RECORD=2|OwnerIndex=1236|OwnerPartId=1|OwnerPartDisplayMode=1|FormalType=1|Electrical=4|PinConglomerate=34|PinLength=10|Location.X=1250|Location.Y=400|Name=1|Designator=1|PinPropagationDelay=0.000000E+000
|RECORD=14|OwnerIndex=1236|IsNotAccesible=T|IndexInSheet=2|OwnerPartId=1|OwnerPartDisplayMode=1|Location.X=1250|Location.Y=396|Corner.X=1270|Corner.Y=404|LineWidth=1|Color=16711680|AreaColor=11599871
|RECORD=2|OwnerIndex=1236|OwnerPartId=1|FormalType=1|Electrical=4|PinConglomerate=32|PinLength=10|Location.X=1270|Location.Y=400|Name=2|Designator=2|PinPropagationDelay=0.000000E+000
|RECORD=2|OwnerIndex=1236|OwnerPartId=1|FormalType=1|Electrical=4|PinConglomerate=34|PinLength=10|Location.X=1250|Location.Y=400|Name=1|Designator=1|PinPropagationDelay=0.000000E+000
|RECORD=6|OwnerIndex=1236|IsNotAccesible=T|IndexInSheet=5|OwnerPartId=1|LineWidth=1|Color=16711680|LocationCount=10|X1=1270|Y1=400|X2=1266|Y2=400|X3=1265|Y3=398|X4=1263|Y4=402|X5=1261|Y5=398|X6=1259|Y6=402|X7=1257|Y7=398|X8=1255|Y8=402|X9=1254|Y9=400|X10=1250|Y10=400
|RECORD=41|OwnerIndex=1236|IndexInSheet=6|OwnerPartId=-1|Location.X=1238|Location.Y=413|Color=8388608|FontID=1|IsHidden=T|Text=Yageo / Phycomp|Name=Manufacturer
|RECORD=41|OwnerIndex=1236|IndexInSheet=7|OwnerPartId=-1|Location.X=1238|Location.Y=413|Color=8388608|FontID=1|IsHidden=T|Text=RC0402FR-0749R9L|Name=Part Number
|RECORD=34|OwnerIndex=1236|IndexInSheet=-1|OwnerPartId=-1|Location.X=1230|Location.Y=400|Color=8388608|FontID=1|Text=R167|Name=Designator|ReadOnlyState=1
|RECORD=41|OwnerIndex=1236|IndexInSheet=-1|OwnerPartId=-1|Location.X=1270|Location.Y=400|Color=8388608|FontID=1|Text=DNI_49.9_1%_0402|Name=Comment
|RECORD=44|OwnerIndex=1236
|RECORD=45|OwnerIndex=1251|IndexInSheet=-1|Description=Chip Resistor, 2-Leads, Body 1.00x0.50mm, IPC High Density|UseComponentLibrary=T|ModelName=RESC1005X40X25LL05T10|ModelType=PCBLIB|DatafileCount=1|ModelDatafileEntity0=RESC1005X40X25LL05T10|ModelDatafileKind0=PCBLib|IsCurrent=T|DatalinksLocked=T|DatabaseDatalinksLocked=T
|RECORD=46|OwnerIndex=1252
|RECORD=48|OwnerIndex=1252
|RECORD=41|OwnerIndex=1254|IndexInSheet=-1|OwnerPartId=-1|Color=8388608|FontID=1|IsHidden=T|Text=2D|Name=Available Preview Images
|RECORD=45|OwnerIndex=1251|IndexInSheet=-1|Description=Chip Resistor, 2-Leads, Body 1.00x0.50mm, IPC Low Density|UseComponentLibrary=T|ModelName=RESC1005X40X25ML05T10|ModelType=PCBLIB|DatafileCount=1|ModelDatafileEntity0=RESC1005X40X25ML05T10|ModelDatafileKind0=PCBLib|DatalinksLocked=T|DatabaseDatalinksLocked=T
|RECORD=46|OwnerIndex=1256
|RECORD=48|OwnerIndex=1256
|RECORD=41|OwnerIndex=1258|IndexInSheet=-1|OwnerPartId=-1|Color=8388608|FontID=1|IsHidden=T|Text=2D|Name=Available Preview Images
|RECORD=45|OwnerIndex=1251|IndexInSheet=-1|Description=Chip Resistor, 2-Leads, Body 1.00x0.50mm, IPC Medium Density|UseComponentLibrary=T|ModelName=RESC1005X40X25NL05T10|ModelType=PCBLIB|DatafileCount=1|ModelDatafileEntity0=RESC1005X40X25NL05T10|ModelDatafileKind0=PCBLib|DatalinksLocked=T|DatabaseDatalinksLocked=T
|RECORD=46|OwnerIndex=1260
|RECORD=48|OwnerIndex=1260
|RECORD=41|OwnerIndex=1262|IndexInSheet=-1|OwnerPartId=-1|Color=8388608|FontID=1|IsHidden=T|Text=2D|Name=Available Preview Images
|RECORD=1|LibReference=RES|PartCount=2|DisplayModeCount=2|IndexInSheet=119|OwnerPartId=-1|Location.X=1250|Location.Y=420|CurrentPartId=1|SourceLibraryName=Altium Content Vault|TargetFileName=*|AreaColor=11599871|Color=128|PartIDLocked=F|DesignItemId=CMP-2002-07709-1|AllPinCount=2|ComponentKindVersion2=5
|RECORD=2|OwnerIndex=1264|OwnerPartId=1|OwnerPartDisplayMode=1|FormalType=1|Electrical=4|PinConglomerate=32|PinLength=10|Location.X=1270|Location.Y=410|Name=2|Designator=2|PinPropagationDelay=0.000000E+000
|RECORD=2|OwnerIndex=1264|OwnerPartId=1|OwnerPartDisplayMode=1|FormalType=1|Electrical=4|PinConglomerate=34|PinLength=10|Location.X=1250|Location.Y=410|Name=1|Designator=1|PinPropagationDelay=0.000000E+000
|RECORD=14|OwnerIndex=1264|IsNotAccesible=T|IndexInSheet=2|OwnerPartId=1|OwnerPartDisplayMode=1|Location.X=1250|Location.Y=406|Corner.X=1270|Corner.Y=414|LineWidth=1|Color=16711680|AreaColor=11599871
|RECORD=2|OwnerIndex=1264|OwnerPartId=1|FormalType=1|Electrical=4|PinConglomerate=32|PinLength=10|Location.X=1270|Location.Y=410|Name=2|Designator=2|PinPropagationDelay=0.000000E+000
|RECORD=2|OwnerIndex=1264|OwnerPartId=1|FormalType=1|Electrical=4|PinConglomerate=34|PinLength=10|Location.X=1250|Location.Y=410|Name=1|Designator=1|PinPropagationDelay=0.000000E+000
|RECORD=6|OwnerIndex=1264|IsNotAccesible=T|IndexInSheet=5|OwnerPartId=1|LineWidth=1|Color=16711680|LocationCount=10|X1=1270|Y1=410|X2=1266|Y2=410|X3=1265|Y3=408|X4=1263|Y4=412|X5=1261|Y5=408|X6=1259|Y6=412|X7=1257|Y7=408|X8=1255|Y8=412|X9=1254|Y9=410|X10=1250|Y10=410
|RECORD=41|OwnerIndex=1264|IndexInSheet=6|OwnerPartId=-1|Location.X=1238|Location.Y=423|Color=8388608|FontID=1|IsHidden=T|Text=Yageo / Phycomp|Name=Manufacturer
|RECORD=41|OwnerIndex=1264|IndexInSheet=7|OwnerPartId=-1|Location.X=1238|Location.Y=423|Color=8388608|FontID=1|IsHidden=T|Text=RC0402FR-0749R9L|Name=Part Number
|RECORD=34|OwnerIndex=1264|IndexInSheet=-1|OwnerPartId=-1|Location.X=1230|Location.Y=410|Color=8388608|FontID=1|Text=R166|Name=Designator|ReadOnlyState=1
|RECORD=41|OwnerIndex=1264|IndexInSheet=-1|OwnerPartId=-1|Location.X=1270|Location.Y=410|Color=8388608|FontID=1|Text=DNI_49.9_1%_0402|Name=Comment
|RECORD=44|OwnerIndex=1264
|RECORD=45|OwnerIndex=1279|IndexInSheet=-1|Description=Chip Resistor, 2-Leads, Body 1.00x0.50mm, IPC High Density|UseComponentLibrary=T|ModelName=RESC1005X40X25LL05T10|ModelType=PCBLIB|DatafileCount=1|ModelDatafileEntity0=RESC1005X40X25LL05T10|ModelDatafileKind0=PCBLib|IsCurrent=T|DatalinksLocked=T|DatabaseDatalinksLocked=T
|RECORD=46|OwnerIndex=1280
|RECORD=48|OwnerIndex=1280
|RECORD=41|OwnerIndex=1282|IndexInSheet=-1|OwnerPartId=-1|Color=8388608|FontID=1|IsHidden=T|Text=2D|Name=Available Preview Images
|RECORD=45|OwnerIndex=1279|IndexInSheet=-1|Description=Chip Resistor, 2-Leads, Body 1.00x0.50mm, IPC Low Density|UseComponentLibrary=T|ModelName=RESC1005X40X25ML05T10|ModelType=PCBLIB|DatafileCount=1|ModelDatafileEntity0=RESC1005X40X25ML05T10|ModelDatafileKind0=PCBLib|DatalinksLocked=T|DatabaseDatalinksLocked=T
|RECORD=46|OwnerIndex=1284
|RECORD=48|OwnerIndex=1284
|RECORD=41|OwnerIndex=1286|IndexInSheet=-1|OwnerPartId=-1|Color=8388608|FontID=1|IsHidden=T|Text=2D|Name=Available Preview Images
|RECORD=45|OwnerIndex=1279|IndexInSheet=-1|Description=Chip Resistor, 2-Leads, Body 1.00x0.50mm, IPC Medium Density|UseComponentLibrary=T|ModelName=RESC1005X40X25NL05T10|ModelType=PCBLIB|DatafileCount=1|ModelDatafileEntity0=RESC1005X40X25NL05T10|ModelDatafileKind0=PCBLib|DatalinksLocked=T|DatabaseDatalinksLocked=T
|RECORD=46|OwnerIndex=1288
|RECORD=48|OwnerIndex=1288
|RECORD=41|OwnerIndex=1290|IndexInSheet=-1|OwnerPartId=-1|Color=8388608|FontID=1|IsHidden=T|Text=2D|Name=Available Preview Images
|RECORD=1|LibReference=RES|PartCount=2|DisplayModeCount=2|IndexInSheet=120|OwnerPartId=-1|Location.X=1250|Location.Y=400|CurrentPartId=1|SourceLibraryName=Altium Content Vault|TargetFileName=*|AreaColor=11599871|Color=128|PartIDLocked=F|DesignItemId=CMP-2002-07709-1|AllPinCount=2|ComponentKindVersion2=5
|RECORD=2|OwnerIndex=1292|OwnerPartId=1|OwnerPartDisplayMode=1|FormalType=1|Electrical=4|PinConglomerate=32|PinLength=10|Location.X=1270|Location.Y=390|Name=2|Designator=2|PinPropagationDelay=0.000000E+000
|RECORD=2|OwnerIndex=1292|OwnerPartId=1|OwnerPartDisplayMode=1|FormalType=1|Electrical=4|PinConglomerate=34|PinLength=10|Location.X=1250|Location.Y=390|Name=1|Designator=1|PinPropagationDelay=0.000000E+000
|RECORD=14|OwnerIndex=1292|IsNotAccesible=T|IndexInSheet=2|OwnerPartId=1|OwnerPartDisplayMode=1|Location.X=1250|Location.Y=386|Corner.X=1270|Corner.Y=394|LineWidth=1|Color=16711680|AreaColor=11599871
|RECORD=2|OwnerIndex=1292|OwnerPartId=1|FormalType=1|Electrical=4|PinConglomerate=32|PinLength=10|Location.X=1270|Location.Y=390|Name=2|Designator=2|PinPropagationDelay=0.000000E+000
|RECORD=2|OwnerIndex=1292|OwnerPartId=1|FormalType=1|Electrical=4|PinConglomerate=34|PinLength=10|Location.X=1250|Location.Y=390|Name=1|Designator=1|PinPropagationDelay=0.000000E+000
|RECORD=6|OwnerIndex=1292|IsNotAccesible=T|IndexInSheet=5|OwnerPartId=1|LineWidth=1|Color=16711680|LocationCount=10|X1=1270|Y1=390|X2=1266|Y2=390|X3=1265|Y3=388|X4=1263|Y4=392|X5=1261|Y5=388|X6=1259|Y6=392|X7=1257|Y7=388|X8=1255|Y8=392|X9=1254|Y9=390|X10=1250|Y10=390
|RECORD=41|OwnerIndex=1292|IndexInSheet=6|OwnerPartId=-1|Location.X=1238|Location.Y=403|Color=8388608|FontID=1|IsHidden=T|Text=Yageo / Phycomp|Name=Manufacturer
|RECORD=41|OwnerIndex=1292|IndexInSheet=7|OwnerPartId=-1|Location.X=1238|Location.Y=403|Color=8388608|FontID=1|IsHidden=T|Text=RC0402FR-0749R9L|Name=Part Number
|RECORD=34|OwnerIndex=1292|IndexInSheet=-1|OwnerPartId=-1|Location.X=1230|Location.Y=390|Color=8388608|FontID=1|Text=R168|Name=Designator|ReadOnlyState=1
|RECORD=41|OwnerIndex=1292|IndexInSheet=-1|OwnerPartId=-1|Location.X=1270|Location.Y=390|Color=8388608|FontID=1|Text=DNI_49.9_1%_0402|Name=Comment
|RECORD=44|OwnerIndex=1292
|RECORD=45|OwnerIndex=1307|IndexInSheet=-1|Description=Chip Resistor, 2-Leads, Body 1.00x0.50mm, IPC High Density|UseComponentLibrary=T|ModelName=RESC1005X40X25LL05T10|ModelType=PCBLIB|DatafileCount=1|ModelDatafileEntity0=RESC1005X40X25LL05T10|ModelDatafileKind0=PCBLib|IsCurrent=T|DatalinksLocked=T|DatabaseDatalinksLocked=T
|RECORD=46|OwnerIndex=1308
|RECORD=48|OwnerIndex=1308
|RECORD=41|OwnerIndex=1310|IndexInSheet=-1|OwnerPartId=-1|Color=8388608|FontID=1|IsHidden=T|Text=2D|Name=Available Preview Images
|RECORD=45|OwnerIndex=1307|IndexInSheet=-1|Description=Chip Resistor, 2-Leads, Body 1.00x0.50mm, IPC Low Density|UseComponentLibrary=T|ModelName=RESC1005X40X25ML05T10|ModelType=PCBLIB|DatafileCount=1|ModelDatafileEntity0=RESC1005X40X25ML05T10|ModelDatafileKind0=PCBLib|DatalinksLocked=T|DatabaseDatalinksLocked=T
|RECORD=46|OwnerIndex=1312
|RECORD=48|OwnerIndex=1312
|RECORD=41|OwnerIndex=1314|IndexInSheet=-1|OwnerPartId=-1|Color=8388608|FontID=1|IsHidden=T|Text=2D|Name=Available Preview Images
|RECORD=45|OwnerIndex=1307|IndexInSheet=-1|Description=Chip Resistor, 2-Leads, Body 1.00x0.50mm, IPC Medium Density|UseComponentLibrary=T|ModelName=RESC1005X40X25NL05T10|ModelType=PCBLIB|DatafileCount=1|ModelDatafileEntity0=RESC1005X40X25NL05T10|ModelDatafileKind0=PCBLib|DatalinksLocked=T|DatabaseDatalinksLocked=T
|RECORD=46|OwnerIndex=1316
|RECORD=48|OwnerIndex=1316
|RECORD=41|OwnerIndex=1318|IndexInSheet=-1|OwnerPartId=-1|Color=8388608|FontID=1|IsHidden=T|Text=2D|Name=Available Preview Images
|RECORD=1|LibReference=RES|PartCount=2|DisplayModeCount=2|IndexInSheet=121|OwnerPartId=-1|Location.X=1120|Location.Y=350|CurrentPartId=1|SourceLibraryName=Altium Content Vault|TargetFileName=*|AreaColor=11599871|Color=128|PartIDLocked=F|DesignItemId=CMP-2002-07709-1|AllPinCount=2
|RECORD=2|OwnerIndex=1320|OwnerPartId=1|OwnerPartDisplayMode=1|FormalType=1|Electrical=4|PinConglomerate=32|PinLength=10|Location.X=1140|Location.Y=340|Name=2|Designator=2|PinPropagationDelay=0.000000E+000
|RECORD=2|OwnerIndex=1320|OwnerPartId=1|OwnerPartDisplayMode=1|FormalType=1|Electrical=4|PinConglomerate=34|PinLength=10|Location.X=1120|Location.Y=340|Name=1|Designator=1|PinPropagationDelay=0.000000E+000
|RECORD=14|OwnerIndex=1320|IsNotAccesible=T|IndexInSheet=2|OwnerPartId=1|OwnerPartDisplayMode=1|Location.X=1120|Location.Y=336|Corner.X=1140|Corner.Y=344|LineWidth=1|Color=16711680|AreaColor=11599871
|RECORD=2|OwnerIndex=1320|OwnerPartId=1|FormalType=1|Electrical=4|PinConglomerate=32|PinLength=10|Location.X=1140|Location.Y=340|Name=2|Designator=2|PinPropagationDelay=0.000000E+000
|RECORD=2|OwnerIndex=1320|OwnerPartId=1|FormalType=1|Electrical=4|PinConglomerate=34|PinLength=10|Location.X=1120|Location.Y=340|Name=1|Designator=1|PinPropagationDelay=0.000000E+000
|RECORD=6|OwnerIndex=1320|IsNotAccesible=T|IndexInSheet=5|OwnerPartId=1|LineWidth=1|Color=16711680|LocationCount=10|X1=1140|Y1=340|X2=1136|Y2=340|X3=1135|Y3=338|X4=1133|Y4=342|X5=1131|Y5=338|X6=1129|Y6=342|X7=1127|Y7=338|X8=1125|Y8=342|X9=1124|Y9=340|X10=1120|Y10=340
|RECORD=41|OwnerIndex=1320|IndexInSheet=6|OwnerPartId=-1|Location.X=1108|Location.Y=353|Color=8388608|FontID=1|IsHidden=T|Text=Yageo / Phycomp|Name=Manufacturer
|RECORD=41|OwnerIndex=1320|IndexInSheet=7|OwnerPartId=-1|Location.X=1108|Location.Y=353|Color=8388608|FontID=1|IsHidden=T|Text=RC0402FR-0749R9L|Name=Part Number
|RECORD=34|OwnerIndex=1320|IndexInSheet=-1|OwnerPartId=-1|Location.X=1100|Location.Y=340|Color=8388608|FontID=1|Text=R171|Name=Designator|ReadOnlyState=1
|RECORD=41|OwnerIndex=1320|IndexInSheet=-1|OwnerPartId=-1|Location.X=1140|Location.Y=340|Color=8388608|FontID=1|Text=49.9_1%_0402|Name=Comment
|RECORD=44|OwnerIndex=1320
|RECORD=45|OwnerIndex=1335|IndexInSheet=-1|Description=Chip Resistor, 2-Leads, Body 1.00x0.50mm, IPC High Density|UseComponentLibrary=T|ModelName=RESC1005X40X25LL05T10|ModelType=PCBLIB|DatafileCount=1|ModelDatafileEntity0=RESC1005X40X25LL05T10|ModelDatafileKind0=PCBLib|IsCurrent=T|DatalinksLocked=T|DatabaseDatalinksLocked=T
|RECORD=46|OwnerIndex=1336
|RECORD=48|OwnerIndex=1336
|RECORD=41|OwnerIndex=1338|IndexInSheet=-1|OwnerPartId=-1|Color=8388608|FontID=1|IsHidden=T|Text=2D|Name=Available Preview Images
|RECORD=45|OwnerIndex=1335|IndexInSheet=-1|Description=Chip Resistor, 2-Leads, Body 1.00x0.50mm, IPC Low Density|UseComponentLibrary=T|ModelName=RESC1005X40X25ML05T10|ModelType=PCBLIB|DatafileCount=1|ModelDatafileEntity0=RESC1005X40X25ML05T10|ModelDatafileKind0=PCBLib|DatalinksLocked=T|DatabaseDatalinksLocked=T
|RECORD=46|OwnerIndex=1340
|RECORD=48|OwnerIndex=1340
|RECORD=41|OwnerIndex=1342|IndexInSheet=-1|OwnerPartId=-1|Color=8388608|FontID=1|IsHidden=T|Text=2D|Name=Available Preview Images
|RECORD=45|OwnerIndex=1335|IndexInSheet=-1|Description=Chip Resistor, 2-Leads, Body 1.00x0.50mm, IPC Medium Density|UseComponentLibrary=T|ModelName=RESC1005X40X25NL05T10|ModelType=PCBLIB|DatafileCount=1|ModelDatafileEntity0=RESC1005X40X25NL05T10|ModelDatafileKind0=PCBLib|DatalinksLocked=T|DatabaseDatalinksLocked=T
|RECORD=46|OwnerIndex=1344
|RECORD=48|OwnerIndex=1344
|RECORD=41|OwnerIndex=1346|IndexInSheet=-1|OwnerPartId=-1|Color=8388608|FontID=1|IsHidden=T|Text=2D|Name=Available Preview Images
|RECORD=1|LibReference=RES|PartCount=2|DisplayModeCount=2|IndexInSheet=122|OwnerPartId=-1|Location.X=1120|Location.Y=310|CurrentPartId=1|SourceLibraryName=Altium Content Vault|TargetFileName=*|AreaColor=11599871|Color=128|PartIDLocked=F|DesignItemId=CMP-2002-07709-1|AllPinCount=2
|RECORD=2|OwnerIndex=1348|OwnerPartId=1|OwnerPartDisplayMode=1|FormalType=1|Electrical=4|PinConglomerate=32|PinLength=10|Location.X=1140|Location.Y=300|Name=2|Designator=2|PinPropagationDelay=0.000000E+000
|RECORD=2|OwnerIndex=1348|OwnerPartId=1|OwnerPartDisplayMode=1|FormalType=1|Electrical=4|PinConglomerate=34|PinLength=10|Location.X=1120|Location.Y=300|Name=1|Designator=1|PinPropagationDelay=0.000000E+000
|RECORD=14|OwnerIndex=1348|IsNotAccesible=T|IndexInSheet=2|OwnerPartId=1|OwnerPartDisplayMode=1|Location.X=1120|Location.Y=296|Corner.X=1140|Corner.Y=304|LineWidth=1|Color=16711680|AreaColor=11599871
|RECORD=2|OwnerIndex=1348|OwnerPartId=1|FormalType=1|Electrical=4|PinConglomerate=32|PinLength=10|Location.X=1140|Location.Y=300|Name=2|Designator=2|PinPropagationDelay=0.000000E+000
|RECORD=2|OwnerIndex=1348|OwnerPartId=1|FormalType=1|Electrical=4|PinConglomerate=34|PinLength=10|Location.X=1120|Location.Y=300|Name=1|Designator=1|PinPropagationDelay=0.000000E+000
|RECORD=6|OwnerIndex=1348|IsNotAccesible=T|IndexInSheet=5|OwnerPartId=1|LineWidth=1|Color=16711680|LocationCount=10|X1=1140|Y1=300|X2=1136|Y2=300|X3=1135|Y3=298|X4=1133|Y4=302|X5=1131|Y5=298|X6=1129|Y6=302|X7=1127|Y7=298|X8=1125|Y8=302|X9=1124|Y9=300|X10=1120|Y10=300
|RECORD=41|OwnerIndex=1348|IndexInSheet=6|OwnerPartId=-1|Location.X=1108|Location.Y=313|Color=8388608|FontID=1|IsHidden=T|Text=Yageo / Phycomp|Name=Manufacturer
|RECORD=41|OwnerIndex=1348|IndexInSheet=7|OwnerPartId=-1|Location.X=1108|Location.Y=313|Color=8388608|FontID=1|IsHidden=T|Text=RC0402FR-0749R9L|Name=Part Number
|RECORD=34|OwnerIndex=1348|IndexInSheet=-1|OwnerPartId=-1|Location.X=1100|Location.Y=300|Color=8388608|FontID=1|Text=R175|Name=Designator|ReadOnlyState=1
|RECORD=41|OwnerIndex=1348|IndexInSheet=-1|OwnerPartId=-1|Location.X=1140|Location.Y=300|Color=8388608|FontID=1|Text=49.9_1%_0402|Name=Comment
|RECORD=44|OwnerIndex=1348
|RECORD=45|OwnerIndex=1363|IndexInSheet=-1|Description=Chip Resistor, 2-Leads, Body 1.00x0.50mm, IPC High Density|UseComponentLibrary=T|ModelName=RESC1005X40X25LL05T10|ModelType=PCBLIB|DatafileCount=1|ModelDatafileEntity0=RESC1005X40X25LL05T10|ModelDatafileKind0=PCBLib|IsCurrent=T|DatalinksLocked=T|DatabaseDatalinksLocked=T
|RECORD=46|OwnerIndex=1364
|RECORD=48|OwnerIndex=1364
|RECORD=41|OwnerIndex=1366|IndexInSheet=-1|OwnerPartId=-1|Color=8388608|FontID=1|IsHidden=T|Text=2D|Name=Available Preview Images
|RECORD=45|OwnerIndex=1363|IndexInSheet=-1|Description=Chip Resistor, 2-Leads, Body 1.00x0.50mm, IPC Low Density|UseComponentLibrary=T|ModelName=RESC1005X40X25ML05T10|ModelType=PCBLIB|DatafileCount=1|ModelDatafileEntity0=RESC1005X40X25ML05T10|ModelDatafileKind0=PCBLib|DatalinksLocked=T|DatabaseDatalinksLocked=T
|RECORD=46|OwnerIndex=1368
|RECORD=48|OwnerIndex=1368
|RECORD=41|OwnerIndex=1370|IndexInSheet=-1|OwnerPartId=-1|Color=8388608|FontID=1|IsHidden=T|Text=2D|Name=Available Preview Images
|RECORD=45|OwnerIndex=1363|IndexInSheet=-1|Description=Chip Resistor, 2-Leads, Body 1.00x0.50mm, IPC Medium Density|UseComponentLibrary=T|ModelName=RESC1005X40X25NL05T10|ModelType=PCBLIB|DatafileCount=1|ModelDatafileEntity0=RESC1005X40X25NL05T10|ModelDatafileKind0=PCBLib|DatalinksLocked=T|DatabaseDatalinksLocked=T
|RECORD=46|OwnerIndex=1372
|RECORD=48|OwnerIndex=1372
|RECORD=41|OwnerIndex=1374|IndexInSheet=-1|OwnerPartId=-1|Color=8388608|FontID=1|IsHidden=T|Text=2D|Name=Available Preview Images
|RECORD=1|LibReference=RES|PartCount=2|DisplayModeCount=2|IndexInSheet=123|OwnerPartId=-1|Location.X=1180|Location.Y=520|CurrentPartId=1|SourceLibraryName=Altium Content Vault|TargetFileName=*|AreaColor=11599871|Color=128|PartIDLocked=F|DesignItemId=CMP-2002-08434-1|AllPinCount=2|ComponentKindVersion2=5
|RECORD=2|OwnerIndex=1376|OwnerPartId=1|OwnerPartDisplayMode=1|FormalType=1|Electrical=4|PinConglomerate=32|PinLength=10|Location.X=1200|Location.Y=510|Name=2|Designator=2|PinPropagationDelay=0.000000E+000
|RECORD=2|OwnerIndex=1376|OwnerPartId=1|OwnerPartDisplayMode=1|FormalType=1|Electrical=4|PinConglomerate=34|PinLength=10|Location.X=1180|Location.Y=510|Name=1|Designator=1|PinPropagationDelay=0.000000E+000
|RECORD=14|OwnerIndex=1376|IsNotAccesible=T|IndexInSheet=2|OwnerPartId=1|OwnerPartDisplayMode=1|Location.X=1180|Location.Y=506|Corner.X=1200|Corner.Y=514|LineWidth=1|Color=16711680|AreaColor=11599871
|RECORD=2|OwnerIndex=1376|OwnerPartId=1|FormalType=1|Electrical=4|PinConglomerate=32|PinLength=10|Location.X=1200|Location.Y=510|Name=2|Designator=2|PinPropagationDelay=0.000000E+000
|RECORD=2|OwnerIndex=1376|OwnerPartId=1|FormalType=1|Electrical=4|PinConglomerate=34|PinLength=10|Location.X=1180|Location.Y=510|Name=1|Designator=1|PinPropagationDelay=0.000000E+000
|RECORD=6|OwnerIndex=1376|IsNotAccesible=T|IndexInSheet=5|OwnerPartId=1|LineWidth=1|Color=16711680|LocationCount=10|X1=1200|Y1=510|X2=1196|Y2=510|X3=1195|Y3=508|X4=1193|Y4=512|X5=1191|Y5=508|X6=1189|Y6=512|X7=1187|Y7=508|X8=1185|Y8=512|X9=1184|Y9=510|X10=1180|Y10=510
|RECORD=41|OwnerIndex=1376|IndexInSheet=6|OwnerPartId=-1|Location.X=1168|Location.Y=523|Color=8388608|FontID=1|IsHidden=T|Text=CRCW040227R0FKED|Name=Part Number
|RECORD=41|OwnerIndex=1376|IndexInSheet=7|OwnerPartId=-1|Location.X=1168|Location.Y=523|Color=8388608|FontID=1|IsHidden=T|Text=Vishay Dale|Name=Manufacturer
|RECORD=34|OwnerIndex=1376|IndexInSheet=-1|OwnerPartId=-1|Location.X=1160|Location.Y=510|Color=8388608|FontID=1|Text=R154|Name=Designator|ReadOnlyState=1
|RECORD=41|OwnerIndex=1376|IndexInSheet=-1|OwnerPartId=-1|Location.X=1180|Location.Y=510|Color=8388608|FontID=1|Text=DNI_27_1%_0402|Name=Comment
|RECORD=44|OwnerIndex=1376
|RECORD=45|OwnerIndex=1391|IndexInSheet=-1|Description=Chip Resistor, 2-Leads, Body 1.00x0.50mm, IPC Medium Density|UseComponentLibrary=T|ModelName=RESC1005X40X25NL05T05|ModelType=PCBLIB|DatafileCount=1|ModelDatafileEntity0=RESC1005X40X25NL05T05|ModelDatafileKind0=PCBLib|IsCurrent=T|DatalinksLocked=T|DatabaseDatalinksLocked=T
|RECORD=46|OwnerIndex=1392
|RECORD=48|OwnerIndex=1392
|RECORD=41|OwnerIndex=1394|IndexInSheet=-1|OwnerPartId=-1|Color=8388608|FontID=1|IsHidden=T|Text=2D|Name=Available Preview Images
|RECORD=45|OwnerIndex=1391|IndexInSheet=-1|Description=Chip Resistor, 2-Leads, Body 1.00x0.50mm, IPC High Density|UseComponentLibrary=T|ModelName=RESC1005X40X25LL05T05|ModelType=PCBLIB|DatafileCount=1|ModelDatafileEntity0=RESC1005X40X25LL05T05|ModelDatafileKind0=PCBLib|DatalinksLocked=T|DatabaseDatalinksLocked=T
|RECORD=46|OwnerIndex=1396
|RECORD=48|OwnerIndex=1396
|RECORD=41|OwnerIndex=1398|IndexInSheet=-1|OwnerPartId=-1|Color=8388608|FontID=1|IsHidden=T|Text=2D|Name=Available Preview Images
|RECORD=45|OwnerIndex=1391|IndexInSheet=-1|Description=Chip Resistor, 2-Leads, Body 1.00x0.50mm, IPC Low Density|UseComponentLibrary=T|ModelName=RESC1005X40X25ML05T05|ModelType=PCBLIB|DatafileCount=1|ModelDatafileEntity0=RESC1005X40X25ML05T05|ModelDatafileKind0=PCBLib|DatalinksLocked=T|DatabaseDatalinksLocked=T
|RECORD=46|OwnerIndex=1400
|RECORD=48|OwnerIndex=1400
|RECORD=41|OwnerIndex=1402|IndexInSheet=-1|OwnerPartId=-1|Color=8388608|FontID=1|IsHidden=T|Text=2D|Name=Available Preview Images
|RECORD=1|LibReference=RES|PartCount=2|DisplayModeCount=2|IndexInSheet=124|OwnerPartId=-1|Location.X=1180|Location.Y=510|CurrentPartId=1|SourceLibraryName=Altium Content Vault|TargetFileName=*|AreaColor=11599871|Color=128|PartIDLocked=F|DesignItemId=CMP-2002-08434-1|AllPinCount=2|ComponentKindVersion2=5
|RECORD=2|OwnerIndex=1404|OwnerPartId=1|OwnerPartDisplayMode=1|FormalType=1|Electrical=4|PinConglomerate=32|PinLength=10|Location.X=1200|Location.Y=500|Name=2|Designator=2|PinPropagationDelay=0.000000E+000
|RECORD=2|OwnerIndex=1404|OwnerPartId=1|OwnerPartDisplayMode=1|FormalType=1|Electrical=4|PinConglomerate=34|PinLength=10|Location.X=1180|Location.Y=500|Name=1|Designator=1|PinPropagationDelay=0.000000E+000
|RECORD=14|OwnerIndex=1404|IsNotAccesible=T|IndexInSheet=2|OwnerPartId=1|OwnerPartDisplayMode=1|Location.X=1180|Location.Y=496|Corner.X=1200|Corner.Y=504|LineWidth=1|Color=16711680|AreaColor=11599871
|RECORD=2|OwnerIndex=1404|OwnerPartId=1|FormalType=1|Electrical=4|PinConglomerate=32|PinLength=10|Location.X=1200|Location.Y=500|Name=2|Designator=2|PinPropagationDelay=0.000000E+000
|RECORD=2|OwnerIndex=1404|OwnerPartId=1|FormalType=1|Electrical=4|PinConglomerate=34|PinLength=10|Location.X=1180|Location.Y=500|Name=1|Designator=1|PinPropagationDelay=0.000000E+000
|RECORD=6|OwnerIndex=1404|IsNotAccesible=T|IndexInSheet=5|OwnerPartId=1|LineWidth=1|Color=16711680|LocationCount=10|X1=1200|Y1=500|X2=1196|Y2=500|X3=1195|Y3=498|X4=1193|Y4=502|X5=1191|Y5=498|X6=1189|Y6=502|X7=1187|Y7=498|X8=1185|Y8=502|X9=1184|Y9=500|X10=1180|Y10=500
|RECORD=41|OwnerIndex=1404|IndexInSheet=6|OwnerPartId=-1|Location.X=1168|Location.Y=513|Color=8388608|FontID=1|IsHidden=T|Text=CRCW040227R0FKED|Name=Part Number
|RECORD=41|OwnerIndex=1404|IndexInSheet=7|OwnerPartId=-1|Location.X=1168|Location.Y=513|Color=8388608|FontID=1|IsHidden=T|Text=Vishay Dale|Name=Manufacturer
|RECORD=34|OwnerIndex=1404|IndexInSheet=-1|OwnerPartId=-1|Location.X=1160|Location.Y=500|Color=8388608|FontID=1|Text=R156|Name=Designator|ReadOnlyState=1
|RECORD=41|OwnerIndex=1404|IndexInSheet=-1|OwnerPartId=-1|Location.X=1180|Location.Y=500|Color=8388608|FontID=1|Text=DNI_27_1%_0402|Name=Comment
|RECORD=44|OwnerIndex=1404
|RECORD=45|OwnerIndex=1419|IndexInSheet=-1|Description=Chip Resistor, 2-Leads, Body 1.00x0.50mm, IPC Medium Density|UseComponentLibrary=T|ModelName=RESC1005X40X25NL05T05|ModelType=PCBLIB|DatafileCount=1|ModelDatafileEntity0=RESC1005X40X25NL05T05|ModelDatafileKind0=PCBLib|IsCurrent=T|DatalinksLocked=T|DatabaseDatalinksLocked=T
|RECORD=46|OwnerIndex=1420
|RECORD=48|OwnerIndex=1420
|RECORD=41|OwnerIndex=1422|IndexInSheet=-1|OwnerPartId=-1|Color=8388608|FontID=1|IsHidden=T|Text=2D|Name=Available Preview Images
|RECORD=45|OwnerIndex=1419|IndexInSheet=-1|Description=Chip Resistor, 2-Leads, Body 1.00x0.50mm, IPC High Density|UseComponentLibrary=T|ModelName=RESC1005X40X25LL05T05|ModelType=PCBLIB|DatafileCount=1|ModelDatafileEntity0=RESC1005X40X25LL05T05|ModelDatafileKind0=PCBLib|DatalinksLocked=T|DatabaseDatalinksLocked=T
|RECORD=46|OwnerIndex=1424
|RECORD=48|OwnerIndex=1424
|RECORD=41|OwnerIndex=1426|IndexInSheet=-1|OwnerPartId=-1|Color=8388608|FontID=1|IsHidden=T|Text=2D|Name=Available Preview Images
|RECORD=45|OwnerIndex=1419|IndexInSheet=-1|Description=Chip Resistor, 2-Leads, Body 1.00x0.50mm, IPC Low Density|UseComponentLibrary=T|ModelName=RESC1005X40X25ML05T05|ModelType=PCBLIB|DatafileCount=1|ModelDatafileEntity0=RESC1005X40X25ML05T05|ModelDatafileKind0=PCBLib|DatalinksLocked=T|DatabaseDatalinksLocked=T
|RECORD=46|OwnerIndex=1428
|RECORD=48|OwnerIndex=1428
|RECORD=41|OwnerIndex=1430|IndexInSheet=-1|OwnerPartId=-1|Color=8388608|FontID=1|IsHidden=T|Text=2D|Name=Available Preview Images
|RECORD=1|LibReference=RES|PartCount=2|DisplayModeCount=2|IndexInSheet=125|OwnerPartId=-1|Location.X=1180|Location.Y=490|CurrentPartId=1|SourceLibraryName=Altium Content Vault|TargetFileName=*|AreaColor=11599871|Color=128|PartIDLocked=F|DesignItemId=CMP-2002-08434-1|AllPinCount=2|ComponentKindVersion2=5
|RECORD=2|OwnerIndex=1432|OwnerPartId=1|OwnerPartDisplayMode=1|FormalType=1|Electrical=4|PinConglomerate=32|PinLength=10|Location.X=1200|Location.Y=480|Name=2|Designator=2|PinPropagationDelay=0.000000E+000
|RECORD=2|OwnerIndex=1432|OwnerPartId=1|OwnerPartDisplayMode=1|FormalType=1|Electrical=4|PinConglomerate=34|PinLength=10|Location.X=1180|Location.Y=480|Name=1|Designator=1|PinPropagationDelay=0.000000E+000
|RECORD=14|OwnerIndex=1432|IsNotAccesible=T|IndexInSheet=2|OwnerPartId=1|OwnerPartDisplayMode=1|Location.X=1180|Location.Y=476|Corner.X=1200|Corner.Y=484|LineWidth=1|Color=16711680|AreaColor=11599871
|RECORD=2|OwnerIndex=1432|OwnerPartId=1|FormalType=1|Electrical=4|PinConglomerate=32|PinLength=10|Location.X=1200|Location.Y=480|Name=2|Designator=2|PinPropagationDelay=0.000000E+000
|RECORD=2|OwnerIndex=1432|OwnerPartId=1|FormalType=1|Electrical=4|PinConglomerate=34|PinLength=10|Location.X=1180|Location.Y=480|Name=1|Designator=1|PinPropagationDelay=0.000000E+000
|RECORD=6|OwnerIndex=1432|IsNotAccesible=T|IndexInSheet=5|OwnerPartId=1|LineWidth=1|Color=16711680|LocationCount=10|X1=1200|Y1=480|X2=1196|Y2=480|X3=1195|Y3=478|X4=1193|Y4=482|X5=1191|Y5=478|X6=1189|Y6=482|X7=1187|Y7=478|X8=1185|Y8=482|X9=1184|Y9=480|X10=1180|Y10=480
|RECORD=41|OwnerIndex=1432|IndexInSheet=6|OwnerPartId=-1|Location.X=1168|Location.Y=493|Color=8388608|FontID=1|IsHidden=T|Text=CRCW040227R0FKED|Name=Part Number
|RECORD=41|OwnerIndex=1432|IndexInSheet=7|OwnerPartId=-1|Location.X=1168|Location.Y=493|Color=8388608|FontID=1|IsHidden=T|Text=Vishay Dale|Name=Manufacturer
|RECORD=34|OwnerIndex=1432|IndexInSheet=-1|OwnerPartId=-1|Location.X=1160|Location.Y=480|Color=8388608|FontID=1|Text=R160|Name=Designator|ReadOnlyState=1
|RECORD=41|OwnerIndex=1432|IndexInSheet=-1|OwnerPartId=-1|Location.X=1180|Location.Y=480|Color=8388608|FontID=1|Text=DNI_27_1%_0402|Name=Comment
|RECORD=44|OwnerIndex=1432
|RECORD=45|OwnerIndex=1447|IndexInSheet=-1|Description=Chip Resistor, 2-Leads, Body 1.00x0.50mm, IPC Medium Density|UseComponentLibrary=T|ModelName=RESC1005X40X25NL05T05|ModelType=PCBLIB|DatafileCount=1|ModelDatafileEntity0=RESC1005X40X25NL05T05|ModelDatafileKind0=PCBLib|IsCurrent=T|DatalinksLocked=T|DatabaseDatalinksLocked=T
|RECORD=46|OwnerIndex=1448
|RECORD=48|OwnerIndex=1448
|RECORD=41|OwnerIndex=1450|IndexInSheet=-1|OwnerPartId=-1|Color=8388608|FontID=1|IsHidden=T|Text=2D|Name=Available Preview Images
|RECORD=45|OwnerIndex=1447|IndexInSheet=-1|Description=Chip Resistor, 2-Leads, Body 1.00x0.50mm, IPC High Density|UseComponentLibrary=T|ModelName=RESC1005X40X25LL05T05|ModelType=PCBLIB|DatafileCount=1|ModelDatafileEntity0=RESC1005X40X25LL05T05|ModelDatafileKind0=PCBLib|DatalinksLocked=T|DatabaseDatalinksLocked=T
|RECORD=46|OwnerIndex=1452
|RECORD=48|OwnerIndex=1452
|RECORD=41|OwnerIndex=1454|IndexInSheet=-1|OwnerPartId=-1|Color=8388608|FontID=1|IsHidden=T|Text=2D|Name=Available Preview Images
|RECORD=45|OwnerIndex=1447|IndexInSheet=-1|Description=Chip Resistor, 2-Leads, Body 1.00x0.50mm, IPC Low Density|UseComponentLibrary=T|ModelName=RESC1005X40X25ML05T05|ModelType=PCBLIB|DatafileCount=1|ModelDatafileEntity0=RESC1005X40X25ML05T05|ModelDatafileKind0=PCBLib|DatalinksLocked=T|DatabaseDatalinksLocked=T
|RECORD=46|OwnerIndex=1456
|RECORD=48|OwnerIndex=1456
|RECORD=41|OwnerIndex=1458|IndexInSheet=-1|OwnerPartId=-1|Color=8388608|FontID=1|IsHidden=T|Text=2D|Name=Available Preview Images
|RECORD=1|LibReference=RES|PartCount=2|DisplayModeCount=2|IndexInSheet=126|OwnerPartId=-1|Location.X=1180|Location.Y=500|CurrentPartId=1|SourceLibraryName=Altium Content Vault|TargetFileName=*|AreaColor=11599871|Color=128|PartIDLocked=F|DesignItemId=CMP-2002-08434-1|AllPinCount=2|ComponentKindVersion2=5
|RECORD=2|OwnerIndex=1460|OwnerPartId=1|OwnerPartDisplayMode=1|FormalType=1|Electrical=4|PinConglomerate=32|PinLength=10|Location.X=1200|Location.Y=490|Name=2|Designator=2|PinPropagationDelay=0.000000E+000
|RECORD=2|OwnerIndex=1460|OwnerPartId=1|OwnerPartDisplayMode=1|FormalType=1|Electrical=4|PinConglomerate=34|PinLength=10|Location.X=1180|Location.Y=490|Name=1|Designator=1|PinPropagationDelay=0.000000E+000
|RECORD=14|OwnerIndex=1460|IsNotAccesible=T|IndexInSheet=2|OwnerPartId=1|OwnerPartDisplayMode=1|Location.X=1180|Location.Y=486|Corner.X=1200|Corner.Y=494|LineWidth=1|Color=16711680|AreaColor=11599871
|RECORD=2|OwnerIndex=1460|OwnerPartId=1|FormalType=1|Electrical=4|PinConglomerate=32|PinLength=10|Location.X=1200|Location.Y=490|Name=2|Designator=2|PinPropagationDelay=0.000000E+000
|RECORD=2|OwnerIndex=1460|OwnerPartId=1|FormalType=1|Electrical=4|PinConglomerate=34|PinLength=10|Location.X=1180|Location.Y=490|Name=1|Designator=1|PinPropagationDelay=0.000000E+000
|RECORD=6|OwnerIndex=1460|IsNotAccesible=T|IndexInSheet=5|OwnerPartId=1|LineWidth=1|Color=16711680|LocationCount=10|X1=1200|Y1=490|X2=1196|Y2=490|X3=1195|Y3=488|X4=1193|Y4=492|X5=1191|Y5=488|X6=1189|Y6=492|X7=1187|Y7=488|X8=1185|Y8=492|X9=1184|Y9=490|X10=1180|Y10=490
|RECORD=41|OwnerIndex=1460|IndexInSheet=6|OwnerPartId=-1|Location.X=1168|Location.Y=503|Color=8388608|FontID=1|IsHidden=T|Text=CRCW040227R0FKED|Name=Part Number
|RECORD=41|OwnerIndex=1460|IndexInSheet=7|OwnerPartId=-1|Location.X=1168|Location.Y=503|Color=8388608|FontID=1|IsHidden=T|Text=Vishay Dale|Name=Manufacturer
|RECORD=34|OwnerIndex=1460|IndexInSheet=-1|OwnerPartId=-1|Location.X=1160|Location.Y=490|Color=8388608|FontID=1|Text=R158|Name=Designator|ReadOnlyState=1
|RECORD=41|OwnerIndex=1460|IndexInSheet=-1|OwnerPartId=-1|Location.X=1180|Location.Y=490|Color=8388608|FontID=1|Text=DNI_27_1%_0402|Name=Comment
|RECORD=44|OwnerIndex=1460
|RECORD=45|OwnerIndex=1475|IndexInSheet=-1|Description=Chip Resistor, 2-Leads, Body 1.00x0.50mm, IPC Medium Density|UseComponentLibrary=T|ModelName=RESC1005X40X25NL05T05|ModelType=PCBLIB|DatafileCount=1|ModelDatafileEntity0=RESC1005X40X25NL05T05|ModelDatafileKind0=PCBLib|IsCurrent=T|DatalinksLocked=T|DatabaseDatalinksLocked=T
|RECORD=46|OwnerIndex=1476
|RECORD=48|OwnerIndex=1476
|RECORD=41|OwnerIndex=1478|IndexInSheet=-1|OwnerPartId=-1|Color=8388608|FontID=1|IsHidden=T|Text=2D|Name=Available Preview Images
|RECORD=45|OwnerIndex=1475|IndexInSheet=-1|Description=Chip Resistor, 2-Leads, Body 1.00x0.50mm, IPC High Density|UseComponentLibrary=T|ModelName=RESC1005X40X25LL05T05|ModelType=PCBLIB|DatafileCount=1|ModelDatafileEntity0=RESC1005X40X25LL05T05|ModelDatafileKind0=PCBLib|DatalinksLocked=T|DatabaseDatalinksLocked=T
|RECORD=46|OwnerIndex=1480
|RECORD=48|OwnerIndex=1480
|RECORD=41|OwnerIndex=1482|IndexInSheet=-1|OwnerPartId=-1|Color=8388608|FontID=1|IsHidden=T|Text=2D|Name=Available Preview Images
|RECORD=45|OwnerIndex=1475|IndexInSheet=-1|Description=Chip Resistor, 2-Leads, Body 1.00x0.50mm, IPC Low Density|UseComponentLibrary=T|ModelName=RESC1005X40X25ML05T05|ModelType=PCBLIB|DatafileCount=1|ModelDatafileEntity0=RESC1005X40X25ML05T05|ModelDatafileKind0=PCBLib|DatalinksLocked=T|DatabaseDatalinksLocked=T
|RECORD=46|OwnerIndex=1484
|RECORD=48|OwnerIndex=1484
|RECORD=41|OwnerIndex=1486|IndexInSheet=-1|OwnerPartId=-1|Color=8388608|FontID=1|IsHidden=T|Text=2D|Name=Available Preview Images
|RECORD=17|IndexInSheet=127|OwnerPartId=-1|ShowNetName=T|Location.X=1410|Location.Y=690|Color=255|FontID=1|Text=GPS2_TX|IsCrossSheetConnector=T
|RECORD=17|IndexInSheet=128|OwnerPartId=-1|ShowNetName=T|Location.X=1130|Location.Y=480|Orientation=2|Color=255|FontID=1|Text=M2_GPS2_TP2|IsCrossSheetConnector=T
|RECORD=17|IndexInSheet=129|OwnerPartId=-1|ShowNetName=T|Location.X=1130|Location.Y=490|Orientation=2|Color=255|FontID=1|Text=M2_GPS2_TP1|IsCrossSheetConnector=T
|RECORD=17|IndexInSheet=130|OwnerPartId=-1|ShowNetName=T|Location.X=1130|Location.Y=500|Orientation=2|Color=255|FontID=1|Text=M2_GPS2_RX|IsCrossSheetConnector=T
|RECORD=17|IndexInSheet=131|OwnerPartId=-1|ShowNetName=T|Location.X=1130|Location.Y=510|Orientation=2|Color=255|FontID=1|Text=M2_GPS2_TX|IsCrossSheetConnector=T
|RECORD=17|IndexInSheet=132|OwnerPartId=-1|ShowNetName=T|Location.X=1230|Location.Y=340|Color=255|FontID=1|Text=GPS2_PIN11|IsCrossSheetConnector=T
|RECORD=17|IndexInSheet=133|OwnerPartId=-1|ShowNetName=T|Location.X=1230|Location.Y=300|Color=255|FontID=1|Text=GPS2_PIN12|IsCrossSheetConnector=T
|RECORD=17|IndexInSheet=134|OwnerPartId=-1|ShowNetName=T|Location.X=860|Location.Y=320|Orientation=2|Color=255|FontID=1|Text=M2_GPS2_PIN11|IsCrossSheetConnector=T
|RECORD=17|IndexInSheet=135|OwnerPartId=-1|ShowNetName=T|Location.X=860|Location.Y=280|Orientation=2|Color=255|FontID=1|Text=M2_GPS2_PIN12|IsCrossSheetConnector=T
|RECORD=17|IndexInSheet=136|OwnerPartId=-1|ShowNetName=T|Location.X=1360|Location.Y=410|Color=255|FontID=1|Text=RCB_GPS2_PIN11|IsCrossSheetConnector=T
|RECORD=17|IndexInSheet=137|OwnerPartId=-1|ShowNetName=T|Location.X=1360|Location.Y=400|Color=255|FontID=1|Text=M2_GPS2_PIN11|IsCrossSheetConnector=T
|RECORD=17|IndexInSheet=138|OwnerPartId=-1|ShowNetName=T|Location.X=1360|Location.Y=390|Color=255|FontID=1|Text=RCB_GPS2_PIN12|IsCrossSheetConnector=T
|RECORD=17|IndexInSheet=139|OwnerPartId=-1|ShowNetName=T|Location.X=1360|Location.Y=380|Color=255|FontID=1|Text=M2_GPS2_PIN12|IsCrossSheetConnector=T
|RECORD=17|IndexInSheet=140|OwnerPartId=-1|ShowNetName=T|Location.X=870|Location.Y=700|Orientation=2|Color=255|FontID=1|Text=RCB_GPS2_TX|IsCrossSheetConnector=T
|RECORD=17|IndexInSheet=141|OwnerPartId=-1|ShowNetName=T|Location.X=1280|Location.Y=680|Color=255|FontID=1|Text=M2_GPS2_TX|IsCrossSheetConnector=T
|RECORD=17|IndexInSheet=142|OwnerPartId=-1|ShowNetName=T|Location.X=1410|Location.Y=610|Color=255|FontID=1|Text=GPS2_RX|IsCrossSheetConnector=T
|RECORD=17|IndexInSheet=143|OwnerPartId=-1|ShowNetName=T|Location.X=1410|Location.Y=620|Color=255|FontID=1|Text=GPS2_TP1|IsCrossSheetConnector=T
|RECORD=17|IndexInSheet=144|OwnerPartId=-1|ShowNetName=T|Location.X=1410|Location.Y=650|Color=255|FontID=1|Text=GPS2_TP2|IsCrossSheetConnector=T
|RECORD=17|IndexInSheet=145|OwnerPartId=-1|ShowNetName=T|Location.X=860|Location.Y=670|Orientation=2|Color=255|FontID=1|Text=RCB_GPS2_RX|IsCrossSheetConnector=T
|RECORD=17|IndexInSheet=146|OwnerPartId=-1|ShowNetName=T|Location.X=1270|Location.Y=630|Color=255|FontID=1|Text=RCB_GPS2_TP1|IsCrossSheetConnector=T
|RECORD=17|IndexInSheet=147|OwnerPartId=-1|ShowNetName=T|Location.X=1270|Location.Y=660|Color=255|FontID=1|Text=RCB_GPS2_TP2|IsCrossSheetConnector=T
|RECORD=17|IndexInSheet=148|OwnerPartId=-1|ShowNetName=T|Location.X=860|Location.Y=680|Orientation=2|Color=255|FontID=1|Text=M2_GPS2_RX|IsCrossSheetConnector=T
|RECORD=17|IndexInSheet=149|OwnerPartId=-1|ShowNetName=T|Location.X=860|Location.Y=650|Orientation=2|Color=255|FontID=1|Text=M2_GPS2_TP1|IsCrossSheetConnector=T
|RECORD=17|IndexInSheet=150|OwnerPartId=-1|ShowNetName=T|Location.X=1270|Location.Y=640|Color=255|FontID=1|Text=M2_GPS2_TP2|IsCrossSheetConnector=T
|RECORD=4|IndexInSheet=151|OwnerPartId=-1|Location.X=250|Location.Y=680|Color=8388608|FontID=1|Text=A = 0, NC <-> COM, A=1, NO <-> COM
|RECORD=4|IndexInSheet=152|OwnerPartId=-1|Location.X=950|Location.Y=750|Color=8388608|FontID=1|Text=A = 0, NC <-> COM, A=1, NO <-> COM
|RECORD=4|IndexInSheet=153|OwnerPartId=-1|Location.X=230|Location.Y=360|Color=8388608|FontID=1|Text=SEL = LL, NC <-> COM , SEL = HH, NO <-> COM
|RECORD=4|IndexInSheet=154|OwnerPartId=-1|Location.X=960|Location.Y=430|Color=8388608|FontID=1|Text=SEL = LL, NC <-> COM , SEL = HH, NO <-> COM
|RECORD=27|IndexInSheet=155|OwnerPartId=-1|LineWidth=1|Color=8388608|LocationCount=4|X1=430|Y1=600|X2=540|Y2=600|X3=540|Y3=730|X4=570|Y4=730
|RECORD=27|IndexInSheet=156|OwnerPartId=-1|LineWidth=1|Color=8388608|LocationCount=4|X1=430|Y1=630|X2=500|Y2=630|X3=500|Y3=660|X4=570|Y4=660
|RECORD=27|IndexInSheet=157|OwnerPartId=-1|LineWidth=1|Color=8388608|LocationCount=2|X1=570|Y1=660|X2=570|Y2=680
|RECORD=27|IndexInSheet=158|OwnerPartId=-1|LineWidth=1|Color=8388608|LocationCount=4|X1=210|Y1=570|X2=160|Y2=570|X3=160|Y3=620|X4=210|Y4=620
|RECORD=27|IndexInSheet=159|OwnerPartId=-1|LineWidth=1|Color=8388608|LocationCount=2|X1=140|Y1=620|X2=160|Y2=620
|RECORD=27|IndexInSheet=160|OwnerPartId=-1|LineWidth=1|Color=8388608|LocationCount=3|X1=210|Y1=590|X2=190|Y2=590|X3=190|Y3=540
|RECORD=27|IndexInSheet=161|OwnerPartId=-1|LineWidth=1|Color=8388608|LocationCount=2|X1=430|Y1=620|X2=460|Y2=620
|RECORD=27|IndexInSheet=162|OwnerPartId=-1|LineWidth=1|Color=8388608|LocationCount=2|X1=430|Y1=580|X2=460|Y2=580
|RECORD=27|IndexInSheet=163|OwnerPartId=-1|LineWidth=1|Color=8388608|LocationCount=2|X1=430|Y1=550|X2=460|Y2=550
|RECORD=27|IndexInSheet=164|OwnerPartId=-1|LineWidth=1|Color=8388608|LocationCount=2|X1=460|Y1=540|X2=430|Y2=540
|RECORD=27|IndexInSheet=165|OwnerPartId=-1|LineWidth=1|Color=8388608|LocationCount=2|X1=240|Y1=140|X2=220|Y2=140
|RECORD=27|IndexInSheet=166|OwnerPartId=-1|LineWidth=1|Color=8388608|LocationCount=4|X1=180|Y1=350|X2=210|Y2=350|X3=210|Y3=290|X4=240|Y4=290
|RECORD=27|IndexInSheet=167|OwnerPartId=-1|LineWidth=1|Color=8388608|LocationCount=2|X1=180|Y1=290|X2=180|Y2=300
|RECORD=27|IndexInSheet=168|OwnerPartId=-1|LineWidth=1|Color=8388608|LocationCount=3|X1=240|Y1=180|X2=220|Y2=180|X3=220|Y3=190
|RECORD=27|IndexInSheet=169|OwnerPartId=-1|LineWidth=1|Color=8388608|LocationCount=3|X1=380|Y1=140|X2=390|Y2=140|X3=390|Y3=130
|RECORD=27|IndexInSheet=170|OwnerPartId=-1|LineWidth=1|Color=8388608|LocationCount=2|X1=150|Y1=270|X2=240|Y2=270
|RECORD=27|IndexInSheet=171|OwnerPartId=-1|LineWidth=1|Color=8388608|LocationCount=2|X1=150|Y1=250|X2=240|Y2=250
|RECORD=27|IndexInSheet=172|OwnerPartId=-1|LineWidth=1|Color=8388608|LocationCount=2|X1=150|Y1=210|X2=240|Y2=210
|RECORD=27|IndexInSheet=173|OwnerPartId=-1|LineWidth=1|Color=8388608|LocationCount=2|X1=240|Y1=230|X2=150|Y2=230
|RECORD=27|IndexInSheet=174|OwnerPartId=-1|LineWidth=1|Color=8388608|LocationCount=2|X1=570|Y1=310|X2=650|Y2=310
|RECORD=27|IndexInSheet=175|OwnerPartId=-1|LineWidth=1|Color=8388608|LocationCount=2|X1=650|Y1=320|X2=570|Y2=320
|RECORD=27|IndexInSheet=176|OwnerPartId=-1|LineWidth=1|Color=8388608|LocationCount=2|X1=570|Y1=330|X2=650|Y2=330
|RECORD=27|IndexInSheet=177|OwnerPartId=-1|LineWidth=1|Color=8388608|LocationCount=2|X1=650|Y1=340|X2=570|Y2=340
|RECORD=27|IndexInSheet=178|OwnerPartId=-1|LineWidth=1|Color=8388608|LocationCount=2|X1=530|Y1=330|X2=460|Y2=330
|RECORD=27|IndexInSheet=179|OwnerPartId=-1|LineWidth=1|Color=8388608|LocationCount=2|X1=530|Y1=310|X2=490|Y2=310
|RECORD=27|IndexInSheet=180|OwnerPartId=-1|LineWidth=1|Color=8388608|LocationCount=2|X1=400|Y1=230|X2=380|Y2=230
|RECORD=27|IndexInSheet=181|OwnerPartId=-1|LineWidth=1|Color=8388608|LocationCount=2|X1=400|Y1=270|X2=380|Y2=270
|RECORD=27|IndexInSheet=182|OwnerPartId=-1|LineWidth=1|Color=8388608|LocationCount=2|X1=420|Y1=500|X2=460|Y2=500
|RECORD=27|IndexInSheet=183|OwnerPartId=-1|LineWidth=1|Color=8388608|LocationCount=2|X1=420|Y1=490|X2=460|Y2=490
|RECORD=27|IndexInSheet=184|OwnerPartId=-1|LineWidth=1|Color=8388608|LocationCount=2|X1=420|Y1=470|X2=460|Y2=470
|RECORD=27|IndexInSheet=185|OwnerPartId=-1|LineWidth=1|Color=8388608|LocationCount=2|X1=420|Y1=480|X2=460|Y2=480
|RECORD=27|IndexInSheet=186|OwnerPartId=-1|LineWidth=1|Color=8388608|LocationCount=2|X1=420|Y1=440|X2=460|Y2=440
|RECORD=27|IndexInSheet=187|OwnerPartId=-1|LineWidth=1|Color=8388608|LocationCount=2|X1=420|Y1=430|X2=460|Y2=430
|RECORD=27|IndexInSheet=188|OwnerPartId=-1|LineWidth=1|Color=8388608|LocationCount=2|X1=420|Y1=410|X2=460|Y2=410
|RECORD=27|IndexInSheet=189|OwnerPartId=-1|LineWidth=1|Color=8388608|LocationCount=2|X1=420|Y1=420|X2=460|Y2=420
|RECORD=27|IndexInSheet=190|OwnerPartId=-1|LineWidth=1|Color=8388608|LocationCount=2|X1=160|Y1=630|X2=210|Y2=630
|RECORD=27|IndexInSheet=191|OwnerPartId=-1|LineWidth=1|Color=8388608|LocationCount=2|X1=430|Y1=610|X2=570|Y2=610
|RECORD=27|IndexInSheet=192|OwnerPartId=-1|LineWidth=1|Color=8388608|LocationCount=2|X1=150|Y1=600|X2=210|Y2=600
|RECORD=27|IndexInSheet=193|OwnerPartId=-1|LineWidth=1|Color=8388608|LocationCount=2|X1=430|Y1=560|X2=560|Y2=560
|RECORD=27|IndexInSheet=194|OwnerPartId=-1|LineWidth=1|Color=8388608|LocationCount=2|X1=430|Y1=590|X2=560|Y2=590
|RECORD=27|IndexInSheet=195|OwnerPartId=-1|LineWidth=1|Color=8388608|LocationCount=2|X1=150|Y1=610|X2=210|Y2=610
|RECORD=27|IndexInSheet=196|OwnerPartId=-1|LineWidth=1|Color=8388608|LocationCount=2|X1=150|Y1=580|X2=210|Y2=580
|RECORD=27|IndexInSheet=197|OwnerPartId=-1|LineWidth=1|Color=8388608|LocationCount=2|X1=430|Y1=570|X2=560|Y2=570
|RECORD=27|IndexInSheet=198|OwnerPartId=-1|LineWidth=1|Color=8388608|LocationCount=3|X1=500|Y1=500|X2=650|Y2=500|X3=650|Y3=620
|RECORD=27|IndexInSheet=199|OwnerPartId=-1|LineWidth=1|Color=8388608|LocationCount=3|X1=500|Y1=490|X2=660|Y2=490|X3=660|Y3=540
|RECORD=27|IndexInSheet=200|OwnerPartId=-1|LineWidth=1|Color=8388608|LocationCount=3|X1=500|Y1=480|X2=670|Y2=480|X3=670|Y3=550
|RECORD=27|IndexInSheet=201|OwnerPartId=-1|LineWidth=1|Color=8388608|LocationCount=3|X1=500|Y1=470|X2=680|Y2=470|X3=680|Y3=580
|RECORD=27|IndexInSheet=202|OwnerPartId=-1|LineWidth=1|Color=8388608|LocationCount=3|X1=500|Y1=440|X2=650|Y2=440|X3=650|Y3=500
|RECORD=27|IndexInSheet=203|OwnerPartId=-1|LineWidth=1|Color=8388608|LocationCount=3|X1=500|Y1=430|X2=660|Y2=430|X3=660|Y3=490
|RECORD=27|IndexInSheet=204|OwnerPartId=-1|LineWidth=1|Color=8388608|LocationCount=3|X1=500|Y1=420|X2=670|Y2=420|X3=670|Y3=480
|RECORD=27|IndexInSheet=205|OwnerPartId=-1|LineWidth=1|Color=8388608|LocationCount=3|X1=500|Y1=410|X2=680|Y2=410|X3=680|Y3=470
|RECORD=27|IndexInSheet=206|OwnerPartId=-1|LineWidth=1|Color=8388608|LocationCount=3|X1=150|Y1=190|X2=220|Y2=190|X3=240|Y3=190
|RECORD=27|IndexInSheet=207|OwnerPartId=-1|LineWidth=1|Color=8388608|LocationCount=4|X1=240|Y1=160|X2=220|Y2=160|X3=220|Y3=140|X4=220|Y4=130
|RECORD=27|IndexInSheet=208|OwnerPartId=-1|LineWidth=1|Color=8388608|LocationCount=3|X1=440|Y1=230|X2=490|Y2=230|X3=520|Y3=230
|RECORD=27|IndexInSheet=209|OwnerPartId=-1|LineWidth=1|Color=8388608|LocationCount=3|X1=440|Y1=270|X2=460|Y2=270|X3=520|Y3=270
|RECORD=27|IndexInSheet=210|OwnerPartId=-1|LineWidth=1|Color=8388608|LocationCount=4|X1=530|Y1=340|X2=460|Y2=340|X3=460|Y3=330|X4=460|Y4=270
|RECORD=27|IndexInSheet=211|OwnerPartId=-1|LineWidth=1|Color=8388608|LocationCount=4|X1=530|Y1=320|X2=490|Y2=320|X3=490|Y3=310|X4=490|Y4=230
|RECORD=27|IndexInSheet=212|OwnerPartId=-1|LineWidth=1|Color=8388608|LocationCount=3|X1=500|Y1=540|X2=660|Y2=540|X3=700|Y3=540
|RECORD=27|IndexInSheet=213|OwnerPartId=-1|LineWidth=1|Color=8388608|LocationCount=3|X1=700|Y1=550|X2=670|Y2=550|X3=500|Y3=550
|RECORD=27|IndexInSheet=214|OwnerPartId=-1|LineWidth=1|Color=8388608|LocationCount=3|X1=500|Y1=580|X2=680|Y2=580|X3=700|Y3=580
|RECORD=27|IndexInSheet=215|OwnerPartId=-1|LineWidth=1|Color=8388608|LocationCount=3|X1=700|Y1=620|X2=650|Y2=620|X3=500|Y3=620
|RECORD=27|IndexInSheet=216|OwnerPartId=-1|LineWidth=1|Color=8388608|LocationCount=3|X1=180|Y1=320|X2=180|Y2=350|X3=180|Y3=370
|RECORD=27|IndexInSheet=217|OwnerPartId=-1|LineWidth=1|Color=8388608|LocationCount=3|X1=570|Y1=700|X2=570|Y2=730|X3=570|Y3=750
|RECORD=27|IndexInSheet=218|OwnerPartId=-1|LineWidth=1|Color=8388608|LocationCount=4|X1=1140|Y1=670|X2=1250|Y2=670|X3=1250|Y3=800|X4=1280|Y4=800
|RECORD=27|IndexInSheet=219|OwnerPartId=-1|LineWidth=1|Color=8388608|LocationCount=4|X1=1140|Y1=700|X2=1210|Y2=700|X3=1210|Y3=730|X4=1280|Y4=730
|RECORD=27|IndexInSheet=220|OwnerPartId=-1|LineWidth=1|Color=8388608|LocationCount=2|X1=1280|Y1=730|X2=1280|Y2=750
|RECORD=27|IndexInSheet=221|OwnerPartId=-1|LineWidth=1|Color=8388608|LocationCount=4|X1=920|Y1=640|X2=870|Y2=640|X3=870|Y3=690|X4=920|Y4=690
|RECORD=27|IndexInSheet=222|OwnerPartId=-1|LineWidth=1|Color=8388608|LocationCount=2|X1=850|Y1=690|X2=870|Y2=690
|RECORD=27|IndexInSheet=223|OwnerPartId=-1|LineWidth=1|Color=8388608|LocationCount=3|X1=920|Y1=660|X2=900|Y2=660|X3=900|Y3=610
|RECORD=27|IndexInSheet=224|OwnerPartId=-1|LineWidth=1|Color=8388608|LocationCount=2|X1=1140|Y1=690|X2=1170|Y2=690
|RECORD=27|IndexInSheet=225|OwnerPartId=-1|LineWidth=1|Color=8388608|LocationCount=2|X1=1140|Y1=650|X2=1170|Y2=650
|RECORD=27|IndexInSheet=226|OwnerPartId=-1|LineWidth=1|Color=8388608|LocationCount=2|X1=1170|Y1=610|X2=1140|Y2=610
|RECORD=27|IndexInSheet=227|OwnerPartId=-1|LineWidth=1|Color=8388608|LocationCount=2|X1=950|Y1=210|X2=930|Y2=210
|RECORD=27|IndexInSheet=228|OwnerPartId=-1|LineWidth=1|Color=8388608|LocationCount=4|X1=890|Y1=420|X2=920|Y2=420|X3=920|Y3=360|X4=950|Y4=360
|RECORD=27|IndexInSheet=229|OwnerPartId=-1|LineWidth=1|Color=8388608|LocationCount=2|X1=890|Y1=360|X2=890|Y2=370
|RECORD=27|IndexInSheet=230|OwnerPartId=-1|LineWidth=1|Color=8388608|LocationCount=3|X1=950|Y1=250|X2=930|Y2=250|X3=930|Y3=260
|RECORD=27|IndexInSheet=231|OwnerPartId=-1|LineWidth=1|Color=8388608|LocationCount=3|X1=1090|Y1=210|X2=1100|Y2=210|X3=1100|Y3=200
|RECORD=27|IndexInSheet=232|OwnerPartId=-1|LineWidth=1|Color=8388608|LocationCount=2|X1=860|Y1=340|X2=950|Y2=340
|RECORD=27|IndexInSheet=233|OwnerPartId=-1|LineWidth=1|Color=8388608|LocationCount=2|X1=860|Y1=320|X2=950|Y2=320
|RECORD=27|IndexInSheet=234|OwnerPartId=-1|LineWidth=1|Color=8388608|LocationCount=2|X1=860|Y1=280|X2=950|Y2=280
|RECORD=27|IndexInSheet=235|OwnerPartId=-1|LineWidth=1|Color=8388608|LocationCount=2|X1=950|Y1=300|X2=860|Y2=300
|RECORD=27|IndexInSheet=236|OwnerPartId=-1|LineWidth=1|Color=8388608|LocationCount=2|X1=1280|Y1=380|X2=1360|Y2=380
|RECORD=27|IndexInSheet=237|OwnerPartId=-1|LineWidth=1|Color=8388608|LocationCount=2|X1=1360|Y1=390|X2=1280|Y2=390
|RECORD=27|IndexInSheet=238|OwnerPartId=-1|LineWidth=1|Color=8388608|LocationCount=2|X1=1280|Y1=400|X2=1360|Y2=400
|RECORD=27|IndexInSheet=239|OwnerPartId=-1|LineWidth=1|Color=8388608|LocationCount=2|X1=1360|Y1=410|X2=1280|Y2=410
|RECORD=27|IndexInSheet=240|OwnerPartId=-1|LineWidth=1|Color=8388608|LocationCount=2|X1=1240|Y1=400|X2=1170|Y2=400
|RECORD=27|IndexInSheet=241|OwnerPartId=-1|LineWidth=1|Color=8388608|LocationCount=2|X1=1240|Y1=380|X2=1200|Y2=380
|RECORD=27|IndexInSheet=242|OwnerPartId=-1|LineWidth=1|Color=8388608|LocationCount=2|X1=1110|Y1=300|X2=1090|Y2=300
|RECORD=27|IndexInSheet=243|OwnerPartId=-1|LineWidth=1|Color=8388608|LocationCount=2|X1=1110|Y1=340|X2=1090|Y2=340
|RECORD=27|IndexInSheet=244|OwnerPartId=-1|LineWidth=1|Color=8388608|LocationCount=2|X1=1130|Y1=570|X2=1170|Y2=570
|RECORD=27|IndexInSheet=245|OwnerPartId=-1|LineWidth=1|Color=8388608|LocationCount=2|X1=1130|Y1=560|X2=1170|Y2=560
|RECORD=27|IndexInSheet=246|OwnerPartId=-1|LineWidth=1|Color=8388608|LocationCount=2|X1=1130|Y1=540|X2=1170|Y2=540
|RECORD=27|IndexInSheet=247|OwnerPartId=-1|LineWidth=1|Color=8388608|LocationCount=2|X1=1130|Y1=550|X2=1170|Y2=550
|RECORD=27|IndexInSheet=248|OwnerPartId=-1|LineWidth=1|Color=8388608|LocationCount=2|X1=1130|Y1=510|X2=1170|Y2=510
|RECORD=27|IndexInSheet=249|OwnerPartId=-1|LineWidth=1|Color=8388608|LocationCount=2|X1=1130|Y1=500|X2=1170|Y2=500
|RECORD=27|IndexInSheet=250|OwnerPartId=-1|LineWidth=1|Color=8388608|LocationCount=2|X1=1130|Y1=480|X2=1170|Y2=480
|RECORD=27|IndexInSheet=251|OwnerPartId=-1|LineWidth=1|Color=8388608|LocationCount=2|X1=1130|Y1=490|X2=1170|Y2=490
|RECORD=27|IndexInSheet=252|OwnerPartId=-1|LineWidth=1|Color=8388608|LocationCount=2|X1=870|Y1=700|X2=920|Y2=700
|RECORD=27|IndexInSheet=253|OwnerPartId=-1|LineWidth=1|Color=8388608|LocationCount=2|X1=1140|Y1=680|X2=1280|Y2=680
|RECORD=27|IndexInSheet=254|OwnerPartId=-1|LineWidth=1|Color=8388608|LocationCount=2|X1=860|Y1=670|X2=920|Y2=670
|RECORD=27|IndexInSheet=255|OwnerPartId=-1|LineWidth=1|Color=8388608|LocationCount=2|X1=1140|Y1=630|X2=1270|Y2=630
|RECORD=27|IndexInSheet=256|OwnerPartId=-1|LineWidth=1|Color=8388608|LocationCount=2|X1=1140|Y1=660|X2=1270|Y2=660
|RECORD=27|IndexInSheet=257|OwnerPartId=-1|LineWidth=1|Color=8388608|LocationCount=2|X1=860|Y1=680|X2=920|Y2=680
|RECORD=27|IndexInSheet=258|OwnerPartId=-1|LineWidth=1|Color=8388608|LocationCount=2|X1=860|Y1=650|X2=920|Y2=650
|RECORD=27|IndexInSheet=259|OwnerPartId=-1|LineWidth=1|Color=8388608|LocationCount=2|X1=1140|Y1=640|X2=1270|Y2=640
|RECORD=27|IndexInSheet=260|OwnerPartId=-1|LineWidth=1|Color=8388608|LocationCount=3|X1=1210|Y1=570|X2=1360|Y2=570|X3=1360|Y3=690
|RECORD=27|IndexInSheet=261|OwnerPartId=-1|LineWidth=1|Color=8388608|LocationCount=3|X1=1210|Y1=560|X2=1370|Y2=560|X3=1370|Y3=610
|RECORD=27|IndexInSheet=262|OwnerPartId=-1|LineWidth=1|Color=8388608|LocationCount=3|X1=1210|Y1=550|X2=1380|Y2=550|X3=1380|Y3=620
|RECORD=27|IndexInSheet=263|OwnerPartId=-1|LineWidth=1|Color=8388608|LocationCount=3|X1=1210|Y1=540|X2=1390|Y2=540|X3=1390|Y3=650
|RECORD=27|IndexInSheet=264|OwnerPartId=-1|LineWidth=1|Color=8388608|LocationCount=3|X1=1210|Y1=510|X2=1360|Y2=510|X3=1360|Y3=570
|RECORD=27|IndexInSheet=265|OwnerPartId=-1|LineWidth=1|Color=8388608|LocationCount=3|X1=1210|Y1=500|X2=1370|Y2=500|X3=1370|Y3=560
|RECORD=27|IndexInSheet=266|OwnerPartId=-1|LineWidth=1|Color=8388608|LocationCount=3|X1=1210|Y1=490|X2=1380|Y2=490|X3=1380|Y3=550
|RECORD=27|IndexInSheet=267|OwnerPartId=-1|LineWidth=1|Color=8388608|LocationCount=3|X1=1210|Y1=480|X2=1390|Y2=480|X3=1390|Y3=540
|RECORD=27|IndexInSheet=268|OwnerPartId=-1|LineWidth=1|Color=8388608|LocationCount=3|X1=860|Y1=260|X2=930|Y2=260|X3=950|Y3=260
|RECORD=27|IndexInSheet=269|OwnerPartId=-1|LineWidth=1|Color=8388608|LocationCount=4|X1=950|Y1=230|X2=930|Y2=230|X3=930|Y3=210|X4=930|Y4=200
|RECORD=27|IndexInSheet=270|OwnerPartId=-1|LineWidth=1|Color=8388608|LocationCount=3|X1=1150|Y1=300|X2=1200|Y2=300|X3=1230|Y3=300
|RECORD=27|IndexInSheet=271|OwnerPartId=-1|LineWidth=1|Color=8388608|LocationCount=3|X1=1150|Y1=340|X2=1170|Y2=340|X3=1230|Y3=340
|RECORD=27|IndexInSheet=272|OwnerPartId=-1|LineWidth=1|Color=8388608|LocationCount=4|X1=1240|Y1=410|X2=1170|Y2=410|X3=1170|Y3=400|X4=1170|Y4=340
|RECORD=27|IndexInSheet=273|OwnerPartId=-1|LineWidth=1|Color=8388608|LocationCount=4|X1=1240|Y1=390|X2=1200|Y2=390|X3=1200|Y3=380|X4=1200|Y4=300
|RECORD=27|IndexInSheet=274|OwnerPartId=-1|LineWidth=1|Color=8388608|LocationCount=3|X1=1210|Y1=610|X2=1370|Y2=610|X3=1410|Y3=610
|RECORD=27|IndexInSheet=275|OwnerPartId=-1|LineWidth=1|Color=8388608|LocationCount=3|X1=1210|Y1=650|X2=1390|Y2=650|X3=1410|Y3=650
|RECORD=27|IndexInSheet=276|OwnerPartId=-1|LineWidth=1|Color=8388608|LocationCount=3|X1=1410|Y1=690|X2=1360|Y2=690|X3=1210|Y3=690
|RECORD=27|IndexInSheet=277|OwnerPartId=-1|LineWidth=1|Color=8388608|LocationCount=3|X1=890|Y1=390|X2=890|Y2=420|X3=890|Y3=440
|RECORD=27|IndexInSheet=278|OwnerPartId=-1|LineWidth=1|Color=8388608|LocationCount=3|X1=1280|Y1=770|X2=1280|Y2=800|X3=1280|Y3=820
|RECORD=27|IndexInSheet=279|OwnerPartId=-1|LineWidth=1|Color=8388608|LocationCount=3|X1=1410|Y1=620|X2=1380|Y2=620|X3=1250|Y3=620
|RECORD=27|IndexInSheet=280|OwnerPartId=-1|LineWidth=1|Color=8388608|LocationCount=2|X1=1140|Y1=620|X2=1210|Y2=620
|RECORD=29|IndexInSheet=-1|OwnerPartId=-1|Location.X=160|Location.Y=620|Color=128
|RECORD=29|IndexInSheet=-1|OwnerPartId=-1|Location.X=180|Location.Y=350|Color=128
|RECORD=29|IndexInSheet=-1|OwnerPartId=-1|Location.X=220|Location.Y=140|Color=128
|RECORD=29|IndexInSheet=-1|OwnerPartId=-1|Location.X=220|Location.Y=190|Color=128
|RECORD=29|IndexInSheet=-1|OwnerPartId=-1|Location.X=460|Location.Y=270|Color=128
|RECORD=29|IndexInSheet=-1|OwnerPartId=-1|Location.X=460|Location.Y=330|Color=128
|RECORD=29|IndexInSheet=-1|OwnerPartId=-1|Location.X=490|Location.Y=230|Color=128
|RECORD=29|IndexInSheet=-1|OwnerPartId=-1|Location.X=490|Location.Y=310|Color=128
|RECORD=29|IndexInSheet=-1|OwnerPartId=-1|Location.X=570|Location.Y=660|Color=128
|RECORD=29|IndexInSheet=-1|OwnerPartId=-1|Location.X=570|Location.Y=730|Color=128
|RECORD=29|IndexInSheet=-1|OwnerPartId=-1|Location.X=650|Location.Y=500|Color=128
|RECORD=29|IndexInSheet=-1|OwnerPartId=-1|Location.X=650|Location.Y=620|Color=128
|RECORD=29|IndexInSheet=-1|OwnerPartId=-1|Location.X=660|Location.Y=490|Color=128
|RECORD=29|IndexInSheet=-1|OwnerPartId=-1|Location.X=660|Location.Y=540|Color=128
|RECORD=29|IndexInSheet=-1|OwnerPartId=-1|Location.X=670|Location.Y=480|Color=128
|RECORD=29|IndexInSheet=-1|OwnerPartId=-1|Location.X=670|Location.Y=550|Color=128
|RECORD=29|IndexInSheet=-1|OwnerPartId=-1|Location.X=680|Location.Y=470|Color=128
|RECORD=29|IndexInSheet=-1|OwnerPartId=-1|Location.X=680|Location.Y=580|Color=128
|RECORD=29|IndexInSheet=-1|OwnerPartId=-1|Location.X=870|Location.Y=690|Color=128
|RECORD=29|IndexInSheet=-1|OwnerPartId=-1|Location.X=890|Location.Y=420|Color=128
|RECORD=29|IndexInSheet=-1|OwnerPartId=-1|Location.X=930|Location.Y=210|Color=128
|RECORD=29|IndexInSheet=-1|OwnerPartId=-1|Location.X=930|Location.Y=260|Color=128
|RECORD=29|IndexInSheet=-1|OwnerPartId=-1|Location.X=1170|Location.Y=340|Color=128
|RECORD=29|IndexInSheet=-1|OwnerPartId=-1|Location.X=1170|Location.Y=400|Color=128
|RECORD=29|IndexInSheet=-1|OwnerPartId=-1|Location.X=1200|Location.Y=300|Color=128
|RECORD=29|IndexInSheet=-1|OwnerPartId=-1|Location.X=1200|Location.Y=380|Color=128
|RECORD=29|IndexInSheet=-1|OwnerPartId=-1|Location.X=1280|Location.Y=730|Color=128
|RECORD=29|IndexInSheet=-1|OwnerPartId=-1|Location.X=1280|Location.Y=800|Color=128
|RECORD=29|IndexInSheet=-1|OwnerPartId=-1|Location.X=1360|Location.Y=570|Color=128
|RECORD=29|IndexInSheet=-1|OwnerPartId=-1|Location.X=1360|Location.Y=690|Color=128
|RECORD=29|IndexInSheet=-1|OwnerPartId=-1|Location.X=1370|Location.Y=560|Color=128
|RECORD=29|IndexInSheet=-1|OwnerPartId=-1|Location.X=1370|Location.Y=610|Color=128
|RECORD=29|IndexInSheet=-1|OwnerPartId=-1|Location.X=1380|Location.Y=550|Color=128
|RECORD=29|IndexInSheet=-1|OwnerPartId=-1|Location.X=1380|Location.Y=620|Color=128
|RECORD=29|IndexInSheet=-1|OwnerPartId=-1|Location.X=1390|Location.Y=540|Color=128
|RECORD=29|IndexInSheet=-1|OwnerPartId=-1|Location.X=1390|Location.Y=650|Color=128